FILE_TYPE = MACRO_DRAWING;
SET COLOR_WIRE YELLOW;
SET COLOR_PROP MONO;
SET COLOR_DOT WHITE;
SET COLOR_ARC YELLOW;
SET COLOR_BODY GREEN;
SET COLOR_NOTE MONO;
SET PROP_DISPLAY VALUE;
SET PAGE_NUMBER P187;
FORCEADD OFFPAGE..1
(-3050 4025);
FORCEPROP 2 LAST $XR0 106 
J 0
(-3302 4025);
DISPLAY 0.638298 (-3302 4025);
PAINT MONO (-3302 4025);
FORCEPROP 2 LAST CDS_LIB mstr_standard
J 0
(-3050 4025);
PAINT ORANGE (-3050 4025);
DISPLAY INVISIBLE (-3050 4025);
FORCEPROP 1 LAST OFFPAGE TRUE
J 0
(-2725 3900);
DISPLAY 0.872340 (-2725 3900);
PAINT GREEN (-2725 3900);
DISPLAY INVISIBLE (-2725 3900);
FORCEPROP 1 LAST COMMENT_BODY TRUE
J 0
(-2925 3925);
DISPLAY 0.872340 (-2925 3925);
PAINT GREEN (-2925 3925);
DISPLAY INVISIBLE (-2925 3925);
FORCEPROP 2 LAST PATH I100
J 0
(-3000 4100);
DISPLAY 1.021277 (-3000 4100);
PAINT ORANGE (-3000 4100);
DISPLAY INVISIBLE (-3000 4100);
FORCEADD TAP..1
(1550 3300);
FORCEPROP 3 LASTPIN (1500 3300) SIG_NAME P3E_CPU0_PE3_OCP_RXP<4>
J 0
(1510 3310);
DISPLAY 0.659574 (1510 3310);
PAINT MONO (1510 3310);
DISPLAY INVISIBLE (1510 3310);
FORCEPROP 1 LASTPIN (1500 3300) BN 4
J 0
(1488 3308);
DISPLAY 0.617021 (1488 3308);
PAINT GREEN (1488 3308);
FORCEPROP 2 LAST CDS_LIB mstr_standard
J 0
(1550 3300);
PAINT ORANGE (1550 3300);
DISPLAY INVISIBLE (1550 3300);
FORCEPROP 1 LAST BODY_TYPE PLUMBING
J 0
(1550 3350);
DISPLAY 0.872340 (1550 3350);
PAINT GREEN (1550 3350);
DISPLAY INVISIBLE (1550 3350);
FORCEPROP 1 LAST HDL_TAP TRUE
J 0
(1875 3175);
DISPLAY 0.872340 (1875 3175);
PAINT ORANGE (1875 3175);
DISPLAY INVISIBLE (1875 3175);
FORCEPROP 1 LAST PATH I111
J 0
(1548 3300);
DISPLAY 0.872340 (1548 3300);
PAINT GREEN (1548 3300);
DISPLAY INVISIBLE (1548 3300);
FORCEADD TAP..1
(1750 3350);
FORCEPROP 3 LASTPIN (1700 3350) SIG_NAME P3E_CPU0_PE3_OCP_RXN<4>
J 0
(1710 3360);
DISPLAY 0.659574 (1710 3360);
PAINT MONO (1710 3360);
DISPLAY INVISIBLE (1710 3360);
FORCEPROP 1 LASTPIN (1700 3350) BN 4
J 0
(1688 3358);
DISPLAY 0.617021 (1688 3358);
PAINT GREEN (1688 3358);
FORCEPROP 2 LAST CDS_LIB mstr_standard
J 0
(1750 3350);
PAINT ORANGE (1750 3350);
DISPLAY INVISIBLE (1750 3350);
FORCEPROP 1 LAST BODY_TYPE PLUMBING
J 0
(1750 3400);
DISPLAY 0.872340 (1750 3400);
PAINT GREEN (1750 3400);
DISPLAY INVISIBLE (1750 3400);
FORCEPROP 1 LAST HDL_TAP TRUE
J 0
(2075 3225);
DISPLAY 0.872340 (2075 3225);
PAINT ORANGE (2075 3225);
DISPLAY INVISIBLE (2075 3225);
FORCEPROP 1 LAST PATH I112
J 0
(1748 3350);
DISPLAY 0.872340 (1748 3350);
PAINT GREEN (1748 3350);
DISPLAY INVISIBLE (1748 3350);
FORCEADD TAP..1
(1750 3550);
FORCEPROP 3 LASTPIN (1700 3550) SIG_NAME P3E_CPU0_PE3_OCP_RXN<5>
J 0
(1710 3560);
DISPLAY 0.659574 (1710 3560);
PAINT MONO (1710 3560);
DISPLAY INVISIBLE (1710 3560);
FORCEPROP 1 LASTPIN (1700 3550) BN 5
J 0
(1688 3558);
DISPLAY 0.617021 (1688 3558);
PAINT GREEN (1688 3558);
FORCEPROP 2 LAST CDS_LIB mstr_standard
J 0
(1750 3550);
PAINT ORANGE (1750 3550);
DISPLAY INVISIBLE (1750 3550);
FORCEPROP 1 LAST BODY_TYPE PLUMBING
J 0
(1750 3600);
DISPLAY 0.872340 (1750 3600);
PAINT GREEN (1750 3600);
DISPLAY INVISIBLE (1750 3600);
FORCEPROP 1 LAST HDL_TAP TRUE
J 0
(2075 3425);
DISPLAY 0.872340 (2075 3425);
PAINT ORANGE (2075 3425);
DISPLAY INVISIBLE (2075 3425);
FORCEPROP 1 LAST PATH I113
J 0
(1748 3550);
DISPLAY 0.872340 (1748 3550);
PAINT GREEN (1748 3550);
DISPLAY INVISIBLE (1748 3550);
FORCEADD TAP..1
(1550 3500);
FORCEPROP 3 LASTPIN (1500 3500) SIG_NAME P3E_CPU0_PE3_OCP_RXP<5>
J 0
(1510 3510);
DISPLAY 0.659574 (1510 3510);
PAINT MONO (1510 3510);
DISPLAY INVISIBLE (1510 3510);
FORCEPROP 1 LASTPIN (1500 3500) BN 5
J 0
(1488 3508);
DISPLAY 0.617021 (1488 3508);
PAINT GREEN (1488 3508);
FORCEPROP 2 LAST CDS_LIB mstr_standard
J 0
(1550 3500);
PAINT ORANGE (1550 3500);
DISPLAY INVISIBLE (1550 3500);
FORCEPROP 1 LAST BODY_TYPE PLUMBING
J 0
(1550 3550);
DISPLAY 0.872340 (1550 3550);
PAINT GREEN (1550 3550);
DISPLAY INVISIBLE (1550 3550);
FORCEPROP 1 LAST HDL_TAP TRUE
J 0
(1875 3375);
DISPLAY 0.872340 (1875 3375);
PAINT ORANGE (1875 3375);
DISPLAY INVISIBLE (1875 3375);
FORCEPROP 1 LAST PATH I114
J 0
(1548 3500);
DISPLAY 0.872340 (1548 3500);
PAINT GREEN (1548 3500);
DISPLAY INVISIBLE (1548 3500);
FORCEADD TAP..1
(1550 3700);
FORCEPROP 3 LASTPIN (1500 3700) SIG_NAME P3E_CPU0_PE3_OCP_RXP<6>
J 0
(1510 3710);
DISPLAY 0.659574 (1510 3710);
PAINT MONO (1510 3710);
DISPLAY INVISIBLE (1510 3710);
FORCEPROP 1 LASTPIN (1500 3700) BN 6
J 0
(1488 3708);
DISPLAY 0.617021 (1488 3708);
PAINT GREEN (1488 3708);
FORCEPROP 2 LAST CDS_LIB mstr_standard
J 0
(1550 3700);
PAINT ORANGE (1550 3700);
DISPLAY INVISIBLE (1550 3700);
FORCEPROP 1 LAST BODY_TYPE PLUMBING
J 0
(1550 3750);
DISPLAY 0.872340 (1550 3750);
PAINT GREEN (1550 3750);
DISPLAY INVISIBLE (1550 3750);
FORCEPROP 1 LAST HDL_TAP TRUE
J 0
(1875 3575);
DISPLAY 0.872340 (1875 3575);
PAINT ORANGE (1875 3575);
DISPLAY INVISIBLE (1875 3575);
FORCEPROP 1 LAST PATH I115
J 0
(1548 3700);
DISPLAY 0.872340 (1548 3700);
PAINT GREEN (1548 3700);
DISPLAY INVISIBLE (1548 3700);
FORCEADD TAP..1
(1750 3750);
FORCEPROP 3 LASTPIN (1700 3750) SIG_NAME P3E_CPU0_PE3_OCP_RXN<6>
J 0
(1710 3760);
DISPLAY 0.659574 (1710 3760);
PAINT MONO (1710 3760);
DISPLAY INVISIBLE (1710 3760);
FORCEPROP 1 LASTPIN (1700 3750) BN 6
J 0
(1688 3758);
DISPLAY 0.617021 (1688 3758);
PAINT GREEN (1688 3758);
FORCEPROP 2 LAST CDS_LIB mstr_standard
J 0
(1750 3750);
PAINT ORANGE (1750 3750);
DISPLAY INVISIBLE (1750 3750);
FORCEPROP 1 LAST BODY_TYPE PLUMBING
J 0
(1750 3800);
DISPLAY 0.872340 (1750 3800);
PAINT GREEN (1750 3800);
DISPLAY INVISIBLE (1750 3800);
FORCEPROP 1 LAST HDL_TAP TRUE
J 0
(2075 3625);
DISPLAY 0.872340 (2075 3625);
PAINT ORANGE (2075 3625);
DISPLAY INVISIBLE (2075 3625);
FORCEPROP 1 LAST PATH I116
J 0
(1748 3750);
DISPLAY 0.872340 (1748 3750);
PAINT GREEN (1748 3750);
DISPLAY INVISIBLE (1748 3750);
FORCEADD SCONN80_E67482007..1
R 2
(-50 3100);
FORCEPROP 1 LAST LOCATION J8E3
J 2
(150 4375);
DISPLAY 0.617021 (150 4375);
PAINT AQUA (150 4375);
FORCEPROP 1 LAST PART_NUMBER E67482-007
J 2
(200 1950);
DISPLAY 0.617021 (200 1950);
PAINT BLUE (200 1950);
FORCEPROP 1 LAST MATERIAL CONN
J 2
(200 4275);
DISPLAY 0.617021 (200 4275);
PAINT SKYBLUE (200 4275);
FORCEPROP 2 LASTPIN (-350 2100) $PN 80
J 2
(-360 2110);
DISPLAY 0.617021 (-360 2110);
PAINT ORANGE (-360 2110);
FORCEPROP 2 LASTPIN (250 2100) $PN 79
J 0
(260 2110);
DISPLAY 0.617021 (260 2110);
PAINT ORANGE (260 2110);
FORCEPROP 2 LASTPIN (-350 2150) $PN 78
J 2
(-360 2160);
DISPLAY 0.617021 (-360 2160);
PAINT ORANGE (-360 2160);
FORCEPROP 2 LASTPIN (250 2150) $PN 77
J 0
(260 2160);
DISPLAY 0.617021 (260 2160);
PAINT ORANGE (260 2160);
FORCEPROP 2 LASTPIN (-350 2200) $PN 76
J 2
(-360 2210);
DISPLAY 0.617021 (-360 2210);
PAINT ORANGE (-360 2210);
FORCEPROP 2 LASTPIN (250 2200) $PN 75
J 0
(260 2210);
DISPLAY 0.617021 (260 2210);
PAINT ORANGE (260 2210);
FORCEPROP 2 LASTPIN (-350 2250) $PN 74
J 2
(-360 2260);
DISPLAY 0.617021 (-360 2260);
PAINT ORANGE (-360 2260);
FORCEPROP 2 LASTPIN (250 2250) $PN 73
J 0
(260 2260);
DISPLAY 0.617021 (260 2260);
PAINT ORANGE (260 2260);
FORCEPROP 2 LASTPIN (-350 2300) $PN 72
J 2
(-360 2310);
DISPLAY 0.617021 (-360 2310);
PAINT ORANGE (-360 2310);
FORCEPROP 2 LASTPIN (250 2300) $PN 71
J 0
(260 2310);
DISPLAY 0.617021 (260 2310);
PAINT ORANGE (260 2310);
FORCEPROP 2 LASTPIN (-350 2350) $PN 70
J 2
(-360 2360);
DISPLAY 0.617021 (-360 2360);
PAINT ORANGE (-360 2360);
FORCEPROP 2 LASTPIN (250 2350) $PN 69
J 0
(260 2360);
DISPLAY 0.617021 (260 2360);
PAINT ORANGE (260 2360);
FORCEPROP 2 LASTPIN (-350 2400) $PN 68
J 2
(-360 2410);
DISPLAY 0.617021 (-360 2410);
PAINT ORANGE (-360 2410);
FORCEPROP 2 LASTPIN (250 2400) $PN 67
J 0
(260 2410);
DISPLAY 0.617021 (260 2410);
PAINT ORANGE (260 2410);
FORCEPROP 2 LASTPIN (-350 2450) $PN 66
J 2
(-360 2460);
DISPLAY 0.617021 (-360 2460);
PAINT ORANGE (-360 2460);
FORCEPROP 2 LASTPIN (250 2450) $PN 65
J 0
(260 2460);
DISPLAY 0.617021 (260 2460);
PAINT ORANGE (260 2460);
FORCEPROP 2 LASTPIN (-350 2500) $PN 64
J 2
(-360 2510);
DISPLAY 0.617021 (-360 2510);
PAINT ORANGE (-360 2510);
FORCEPROP 2 LASTPIN (250 2500) $PN 63
J 0
(260 2510);
DISPLAY 0.617021 (260 2510);
PAINT ORANGE (260 2510);
FORCEPROP 2 LASTPIN (-350 2550) $PN 62
J 2
(-360 2560);
DISPLAY 0.617021 (-360 2560);
PAINT ORANGE (-360 2560);
FORCEPROP 2 LASTPIN (250 2550) $PN 61
J 0
(260 2560);
DISPLAY 0.617021 (260 2560);
PAINT ORANGE (260 2560);
FORCEPROP 2 LASTPIN (-350 2600) $PN 60
J 2
(-360 2610);
DISPLAY 0.617021 (-360 2610);
PAINT ORANGE (-360 2610);
FORCEPROP 2 LASTPIN (250 2600) $PN 59
J 0
(260 2610);
DISPLAY 0.617021 (260 2610);
PAINT ORANGE (260 2610);
FORCEPROP 2 LASTPIN (-350 2650) $PN 58
J 2
(-360 2660);
DISPLAY 0.617021 (-360 2660);
PAINT ORANGE (-360 2660);
FORCEPROP 2 LASTPIN (250 2650) $PN 57
J 0
(260 2660);
DISPLAY 0.617021 (260 2660);
PAINT ORANGE (260 2660);
FORCEPROP 2 LASTPIN (-350 2700) $PN 56
J 2
(-360 2710);
DISPLAY 0.617021 (-360 2710);
PAINT ORANGE (-360 2710);
FORCEPROP 2 LASTPIN (250 2700) $PN 55
J 0
(260 2710);
DISPLAY 0.617021 (260 2710);
PAINT ORANGE (260 2710);
FORCEPROP 2 LASTPIN (-350 2750) $PN 54
J 2
(-360 2760);
DISPLAY 0.617021 (-360 2760);
PAINT ORANGE (-360 2760);
FORCEPROP 2 LASTPIN (250 2750) $PN 53
J 0
(260 2760);
DISPLAY 0.617021 (260 2760);
PAINT ORANGE (260 2760);
FORCEPROP 2 LASTPIN (-350 2800) $PN 52
J 2
(-360 2810);
DISPLAY 0.617021 (-360 2810);
PAINT ORANGE (-360 2810);
FORCEPROP 2 LASTPIN (250 2800) $PN 51
J 0
(260 2810);
DISPLAY 0.617021 (260 2810);
PAINT ORANGE (260 2810);
FORCEPROP 2 LASTPIN (-350 2850) $PN 50
J 2
(-360 2860);
DISPLAY 0.617021 (-360 2860);
PAINT ORANGE (-360 2860);
FORCEPROP 2 LASTPIN (250 2850) $PN 49
J 0
(260 2860);
DISPLAY 0.617021 (260 2860);
PAINT ORANGE (260 2860);
FORCEPROP 2 LASTPIN (-350 2900) $PN 48
J 2
(-360 2910);
DISPLAY 0.617021 (-360 2910);
PAINT ORANGE (-360 2910);
FORCEPROP 2 LASTPIN (250 2900) $PN 47
J 0
(260 2910);
DISPLAY 0.617021 (260 2910);
PAINT ORANGE (260 2910);
FORCEPROP 2 LASTPIN (-350 2950) $PN 46
J 2
(-360 2960);
DISPLAY 0.617021 (-360 2960);
PAINT ORANGE (-360 2960);
FORCEPROP 2 LASTPIN (250 2950) $PN 45
J 0
(260 2960);
DISPLAY 0.617021 (260 2960);
PAINT ORANGE (260 2960);
FORCEPROP 2 LASTPIN (-350 3000) $PN 44
J 2
(-360 3010);
DISPLAY 0.617021 (-360 3010);
PAINT ORANGE (-360 3010);
FORCEPROP 2 LASTPIN (250 3000) $PN 43
J 0
(260 3010);
DISPLAY 0.617021 (260 3010);
PAINT ORANGE (260 3010);
FORCEPROP 2 LASTPIN (-350 3050) $PN 42
J 2
(-360 3060);
DISPLAY 0.617021 (-360 3060);
PAINT ORANGE (-360 3060);
FORCEPROP 2 LASTPIN (250 3050) $PN 41
J 0
(260 3060);
DISPLAY 0.617021 (260 3060);
PAINT ORANGE (260 3060);
FORCEPROP 2 LASTPIN (-350 3100) $PN 40
J 2
(-360 3110);
DISPLAY 0.617021 (-360 3110);
PAINT ORANGE (-360 3110);
FORCEPROP 2 LASTPIN (250 3100) $PN 39
J 0
(260 3110);
DISPLAY 0.617021 (260 3110);
PAINT ORANGE (260 3110);
FORCEPROP 2 LASTPIN (-350 3150) $PN 38
J 2
(-360 3160);
DISPLAY 0.617021 (-360 3160);
PAINT ORANGE (-360 3160);
FORCEPROP 2 LASTPIN (250 3150) $PN 37
J 0
(260 3160);
DISPLAY 0.617021 (260 3160);
PAINT ORANGE (260 3160);
FORCEPROP 2 LASTPIN (-350 3200) $PN 36
J 2
(-360 3210);
DISPLAY 0.617021 (-360 3210);
PAINT ORANGE (-360 3210);
FORCEPROP 2 LASTPIN (250 3200) $PN 35
J 0
(260 3210);
DISPLAY 0.617021 (260 3210);
PAINT ORANGE (260 3210);
FORCEPROP 2 LASTPIN (-350 3250) $PN 34
J 2
(-360 3260);
DISPLAY 0.617021 (-360 3260);
PAINT ORANGE (-360 3260);
FORCEPROP 2 LASTPIN (250 3250) $PN 33
J 0
(260 3260);
DISPLAY 0.617021 (260 3260);
PAINT ORANGE (260 3260);
FORCEPROP 2 LASTPIN (-350 3300) $PN 32
J 2
(-360 3310);
DISPLAY 0.617021 (-360 3310);
PAINT ORANGE (-360 3310);
FORCEPROP 2 LASTPIN (250 3300) $PN 31
J 0
(260 3310);
DISPLAY 0.617021 (260 3310);
PAINT ORANGE (260 3310);
FORCEPROP 2 LASTPIN (-350 3350) $PN 30
J 2
(-360 3360);
DISPLAY 0.617021 (-360 3360);
PAINT ORANGE (-360 3360);
FORCEPROP 2 LASTPIN (250 3350) $PN 29
J 0
(260 3360);
DISPLAY 0.617021 (260 3360);
PAINT ORANGE (260 3360);
FORCEPROP 2 LASTPIN (-350 3400) $PN 28
J 2
(-360 3410);
DISPLAY 0.617021 (-360 3410);
PAINT ORANGE (-360 3410);
FORCEPROP 2 LASTPIN (250 3400) $PN 27
J 0
(260 3410);
DISPLAY 0.617021 (260 3410);
PAINT ORANGE (260 3410);
FORCEPROP 2 LASTPIN (-350 3450) $PN 26
J 2
(-360 3460);
DISPLAY 0.617021 (-360 3460);
PAINT ORANGE (-360 3460);
FORCEPROP 2 LASTPIN (250 3450) $PN 25
J 0
(260 3460);
DISPLAY 0.617021 (260 3460);
PAINT ORANGE (260 3460);
FORCEPROP 2 LASTPIN (-350 3500) $PN 24
J 2
(-360 3510);
DISPLAY 0.617021 (-360 3510);
PAINT ORANGE (-360 3510);
FORCEPROP 2 LASTPIN (250 3500) $PN 23
J 0
(260 3510);
DISPLAY 0.617021 (260 3510);
PAINT ORANGE (260 3510);
FORCEPROP 2 LASTPIN (-350 3550) $PN 22
J 2
(-360 3560);
DISPLAY 0.617021 (-360 3560);
PAINT ORANGE (-360 3560);
FORCEPROP 2 LASTPIN (250 3550) $PN 21
J 0
(260 3560);
DISPLAY 0.617021 (260 3560);
PAINT ORANGE (260 3560);
FORCEPROP 2 LASTPIN (-350 3600) $PN 20
J 2
(-360 3610);
DISPLAY 0.617021 (-360 3610);
PAINT ORANGE (-360 3610);
FORCEPROP 2 LASTPIN (250 3600) $PN 19
J 0
(260 3610);
DISPLAY 0.617021 (260 3610);
PAINT ORANGE (260 3610);
FORCEPROP 2 LASTPIN (-350 3650) $PN 18
J 2
(-360 3660);
DISPLAY 0.617021 (-360 3660);
PAINT ORANGE (-360 3660);
FORCEPROP 2 LASTPIN (250 3650) $PN 17
J 0
(260 3660);
DISPLAY 0.617021 (260 3660);
PAINT ORANGE (260 3660);
FORCEPROP 2 LASTPIN (-350 3700) $PN 16
J 2
(-360 3710);
DISPLAY 0.617021 (-360 3710);
PAINT ORANGE (-360 3710);
FORCEPROP 2 LASTPIN (250 3700) $PN 15
J 0
(260 3710);
DISPLAY 0.617021 (260 3710);
PAINT ORANGE (260 3710);
FORCEPROP 2 LASTPIN (-350 3750) $PN 14
J 2
(-360 3760);
DISPLAY 0.617021 (-360 3760);
PAINT ORANGE (-360 3760);
FORCEPROP 2 LASTPIN (250 3750) $PN 13
J 0
(260 3760);
DISPLAY 0.617021 (260 3760);
PAINT ORANGE (260 3760);
FORCEPROP 2 LASTPIN (-350 3800) $PN 12
J 2
(-360 3810);
DISPLAY 0.617021 (-360 3810);
PAINT ORANGE (-360 3810);
FORCEPROP 2 LASTPIN (250 3800) $PN 11
J 0
(260 3810);
DISPLAY 0.617021 (260 3810);
PAINT ORANGE (260 3810);
FORCEPROP 2 LASTPIN (-350 3850) $PN 10
J 2
(-360 3860);
DISPLAY 0.617021 (-360 3860);
PAINT ORANGE (-360 3860);
FORCEPROP 2 LASTPIN (250 3850) $PN 9
J 0
(260 3860);
DISPLAY 0.617021 (260 3860);
PAINT ORANGE (260 3860);
FORCEPROP 2 LASTPIN (-350 3900) $PN 8
J 2
(-360 3910);
DISPLAY 0.617021 (-360 3910);
PAINT ORANGE (-360 3910);
FORCEPROP 2 LASTPIN (250 3900) $PN 7
J 0
(260 3910);
DISPLAY 0.617021 (260 3910);
PAINT ORANGE (260 3910);
FORCEPROP 2 LASTPIN (-350 3950) $PN 6
J 2
(-360 3960);
DISPLAY 0.617021 (-360 3960);
PAINT ORANGE (-360 3960);
FORCEPROP 2 LASTPIN (250 3950) $PN 5
J 0
(260 3960);
DISPLAY 0.617021 (260 3960);
PAINT ORANGE (260 3960);
FORCEPROP 2 LASTPIN (-350 4000) $PN 4
J 2
(-360 4010);
DISPLAY 0.617021 (-360 4010);
PAINT ORANGE (-360 4010);
FORCEPROP 2 LASTPIN (250 4000) $PN 3
J 0
(260 4010);
DISPLAY 0.617021 (260 4010);
PAINT ORANGE (260 4010);
FORCEPROP 2 LASTPIN (-350 4050) $PN 2
J 2
(-360 4060);
DISPLAY 0.617021 (-360 4060);
PAINT ORANGE (-360 4060);
FORCEPROP 2 LASTPIN (250 4050) $PN 1
J 0
(260 4060);
DISPLAY 0.617021 (260 4060);
PAINT ORANGE (260 4060);
FORCEPROP 1 LAST PACK_TYPE SM
J 2
(200 4375);
PAINT SKYBLUE (200 4375);
DISPLAY INVISIBLE (200 4375);
FORCEPROP 1 LAST CDS_LMAN_SYM_OUTLINE -250,1100,250,-1100
J 2
(-50 3100);
DISPLAY 0.468085 (-50 3100);
PAINT GREEN (-50 3100);
DISPLAY INVISIBLE (-50 3100);
FORCEPROP 2 LAST CDS_LIB mstr_sconn
J 0
(-50 3100);
PAINT ORANGE (-50 3100);
DISPLAY INVISIBLE (-50 3100);
FORCEPROP 2 LAST SEC_TYPE SM
J 0
(200 4350);
DISPLAY 1.021277 (200 4350);
PAINT ORANGE (200 4350);
DISPLAY INVISIBLE (200 4350);
FORCEPROP 2 LAST SEC 1
J 0
(200 4350);
DISPLAY 0.680851 (200 4350);
PAINT MONO (200 4350);
DISPLAY INVISIBLE (200 4350);
FORCEPROP 2 LAST CDS_LOCATION J8E3
J 2
(150 4375);
DISPLAY 0.617021 (150 4375);
PAINT AQUA (150 4375);
DISPLAY INVISIBLE (150 4375);
FORCEPROP 1 LAST PATH I119
J 2
(-50 4276);
PAINT GREEN (-50 4276);
DISPLAY INVISIBLE (-50 4276);
FORCEPROP 0 LAST ROOM IO_SLOT
J 2
(200 4400);
DISPLAY 1.021277 (200 4400);
PAINT ORANGE (200 4400);
DISPLAY INVISIBLE (200 4400);
FORCEADD TAP..1
(1750 2700);
FORCEPROP 3 LASTPIN (1700 2700) SIG_NAME P3E_CPU0_PE3_OCP_RXN<1>
J 0
(1710 2710);
DISPLAY 0.659574 (1710 2710);
PAINT MONO (1710 2710);
DISPLAY INVISIBLE (1710 2710);
FORCEPROP 1 LASTPIN (1700 2700) BN 1
J 0
(1688 2708);
DISPLAY 0.617021 (1688 2708);
PAINT GREEN (1688 2708);
FORCEPROP 2 LAST CDS_LIB mstr_standard
J 0
(1750 2700);
PAINT ORANGE (1750 2700);
DISPLAY INVISIBLE (1750 2700);
FORCEPROP 1 LAST BODY_TYPE PLUMBING
J 0
(1750 2750);
DISPLAY 0.872340 (1750 2750);
PAINT GREEN (1750 2750);
DISPLAY INVISIBLE (1750 2750);
FORCEPROP 1 LAST HDL_TAP TRUE
J 0
(2075 2575);
DISPLAY 0.872340 (2075 2575);
PAINT ORANGE (2075 2575);
DISPLAY INVISIBLE (2075 2575);
FORCEPROP 1 LAST PATH I140
J 0
(1748 2700);
DISPLAY 0.872340 (1748 2700);
PAINT GREEN (1748 2700);
DISPLAY INVISIBLE (1748 2700);
FORCEADD TAP..1
(1750 2900);
FORCEPROP 3 LASTPIN (1700 2900) SIG_NAME P3E_CPU0_PE3_OCP_RXN<2>
J 0
(1710 2910);
DISPLAY 0.659574 (1710 2910);
PAINT MONO (1710 2910);
DISPLAY INVISIBLE (1710 2910);
FORCEPROP 1 LASTPIN (1700 2900) BN 2
J 0
(1688 2908);
DISPLAY 0.617021 (1688 2908);
PAINT GREEN (1688 2908);
FORCEPROP 2 LAST CDS_LIB mstr_standard
J 0
(1750 2900);
PAINT ORANGE (1750 2900);
DISPLAY INVISIBLE (1750 2900);
FORCEPROP 1 LAST BODY_TYPE PLUMBING
J 0
(1750 2950);
DISPLAY 0.872340 (1750 2950);
PAINT GREEN (1750 2950);
DISPLAY INVISIBLE (1750 2950);
FORCEPROP 1 LAST HDL_TAP TRUE
J 0
(2075 2775);
DISPLAY 0.872340 (2075 2775);
PAINT ORANGE (2075 2775);
DISPLAY INVISIBLE (2075 2775);
FORCEPROP 1 LAST PATH I141
J 0
(1748 2900);
DISPLAY 0.872340 (1748 2900);
PAINT GREEN (1748 2900);
DISPLAY INVISIBLE (1748 2900);
FORCEADD TAP..1
(1550 2950);
FORCEPROP 3 LASTPIN (1500 2950) SIG_NAME P3E_CPU0_PE3_OCP_RXP<2>
J 0
(1510 2960);
DISPLAY 0.659574 (1510 2960);
PAINT MONO (1510 2960);
DISPLAY INVISIBLE (1510 2960);
FORCEPROP 1 LASTPIN (1500 2950) BN 2
J 0
(1488 2958);
DISPLAY 0.617021 (1488 2958);
PAINT GREEN (1488 2958);
FORCEPROP 2 LAST CDS_LIB mstr_standard
J 0
(1550 2950);
PAINT ORANGE (1550 2950);
DISPLAY INVISIBLE (1550 2950);
FORCEPROP 1 LAST BODY_TYPE PLUMBING
J 0
(1550 3000);
DISPLAY 0.872340 (1550 3000);
PAINT GREEN (1550 3000);
DISPLAY INVISIBLE (1550 3000);
FORCEPROP 1 LAST HDL_TAP TRUE
J 0
(1875 2825);
DISPLAY 0.872340 (1875 2825);
PAINT ORANGE (1875 2825);
DISPLAY INVISIBLE (1875 2825);
FORCEPROP 1 LAST PATH I142
J 0
(1548 2950);
DISPLAY 0.872340 (1548 2950);
PAINT GREEN (1548 2950);
DISPLAY INVISIBLE (1548 2950);
FORCEADD OFFPAGE..1
R 2
(3000 2200);
FORCEPROP 2 LAST $XR0 190 
J 0
(3186 2200);
DISPLAY 0.638298 (3186 2200);
PAINT MONO (3186 2200);
FORCEPROP 2 LAST CDS_LIB mstr_standard
J 0
(3000 2200);
PAINT ORANGE (3000 2200);
DISPLAY INVISIBLE (3000 2200);
FORCEPROP 1 LAST OFFPAGE TRUE
J 2
(2675 2075);
DISPLAY 0.872340 (2675 2075);
PAINT GREEN (2675 2075);
DISPLAY INVISIBLE (2675 2075);
FORCEPROP 1 LAST COMMENT_BODY TRUE
J 2
(2875 2100);
DISPLAY 0.872340 (2875 2100);
PAINT GREEN (2875 2100);
DISPLAY INVISIBLE (2875 2100);
FORCEPROP 2 LAST PATH I143
J 0
(3200 2250);
DISPLAY 1.021277 (3200 2250);
PAINT ORANGE (3200 2250);
DISPLAY INVISIBLE (3200 2250);
FORCEADD OFFPAGE..1
R 2
(3000 2150);
FORCEPROP 2 LAST $XR0 190 
J 0
(3186 2150);
DISPLAY 0.638298 (3186 2150);
PAINT MONO (3186 2150);
FORCEPROP 2 LAST CDS_LIB mstr_standard
J 0
(3000 2150);
PAINT ORANGE (3000 2150);
DISPLAY INVISIBLE (3000 2150);
FORCEPROP 1 LAST OFFPAGE TRUE
J 2
(2675 2025);
DISPLAY 0.872340 (2675 2025);
PAINT GREEN (2675 2025);
DISPLAY INVISIBLE (2675 2025);
FORCEPROP 1 LAST COMMENT_BODY TRUE
J 2
(2875 2050);
DISPLAY 0.872340 (2875 2050);
PAINT GREEN (2875 2050);
DISPLAY INVISIBLE (2875 2050);
FORCEPROP 2 LAST PATH I144
J 0
(3200 2200);
DISPLAY 1.021277 (3200 2200);
PAINT ORANGE (3200 2200);
DISPLAY INVISIBLE (3200 2200);
FORCEADD RES..1
(2275 2200);
FORCEPROP 1 LAST LOCATION R9E10
J 0
(2225 2250);
DISPLAY 0.617021 (2225 2250);
PAINT AQUA (2225 2250);
FORCEPROP 1 LAST PART_NUMBER G21796-004
J 0
(2100 2150);
DISPLAY 0.617021 (2100 2150);
PAINT BLUE (2100 2150);
FORCEPROP 1 LAST VALUE 200.0
J 2
(2250 2100);
DISPLAY 0.617021 (2250 2100);
PAINT SKYBLUE (2250 2100);
FORCEPROP 1 LAST TOLERANCE 1%
J 0
(2275 2100);
DISPLAY 0.617021 (2275 2100);
PAINT SKYBLUE (2275 2100);
FORCEPROP 1 LAST PACK_TYPE 0402
J 0
(2375 2125);
DISPLAY 0.617021 (2375 2125);
PAINT SKYBLUE (2375 2125);
FORCEPROP 1 LAST MATERIAL CHIP
J 0
(2275 2050);
DISPLAY 0.617021 (2275 2050);
PAINT SKYBLUE (2275 2050);
FORCEPROP 1 LAST WATTAGE 1/16W
J 2
(2250 2050);
DISPLAY 0.617021 (2250 2050);
PAINT SKYBLUE (2250 2050);
FORCEPROP 1 LASTPIN (2375 2200) $PN 2
J 0
(2337 2212);
DISPLAY 0.617021 (2337 2212);
PAINT ORANGE (2337 2212);
FORCEPROP 1 LASTPIN (2175 2200) $PN 1
J 0
(2187 2212);
DISPLAY 0.617021 (2187 2212);
PAINT ORANGE (2187 2212);
FORCEPROP 2 LAST CDS_LIB mstr_discrete
J 0
(2275 2200);
PAINT ORANGE (2275 2200);
DISPLAY INVISIBLE (2275 2200);
FORCEPROP 2 LAST SEC_TYPE 0402
J 0
(2225 2400);
DISPLAY 1.021277 (2225 2400);
PAINT ORANGE (2225 2400);
DISPLAY INVISIBLE (2225 2400);
FORCEPROP 2 LAST SEC 1
J 0
(2225 2400);
DISPLAY 0.680851 (2225 2400);
PAINT MONO (2225 2400);
DISPLAY INVISIBLE (2225 2400);
FORCEPROP 2 LAST CDS_LOCATION R9E10
J 0
(2225 2250);
DISPLAY 0.617021 (2225 2250);
PAINT AQUA (2225 2250);
DISPLAY INVISIBLE (2225 2250);
FORCEPROP 1 LAST PATH I145
J 0
(2225 2350);
DISPLAY 0.978723 (2225 2350);
PAINT WHITE (2225 2350);
DISPLAY INVISIBLE (2225 2350);
FORCEPROP 0 LAST ROOM IO_SLOT
J 0
(2225 2400);
DISPLAY 1.021277 (2225 2400);
PAINT ORANGE (2225 2400);
DISPLAY INVISIBLE (2225 2400);
FORCEADD OFFPAGE..1
R 2
(3000 2100);
FORCEPROP 2 LAST $XR0 190 
J 0
(3186 2100);
DISPLAY 0.638298 (3186 2100);
PAINT MONO (3186 2100);
FORCEPROP 2 LAST CDS_LIB mstr_standard
J 0
(3000 2100);
PAINT ORANGE (3000 2100);
DISPLAY INVISIBLE (3000 2100);
FORCEPROP 1 LAST OFFPAGE TRUE
J 2
(2675 1975);
DISPLAY 0.872340 (2675 1975);
PAINT GREEN (2675 1975);
DISPLAY INVISIBLE (2675 1975);
FORCEPROP 1 LAST COMMENT_BODY TRUE
J 2
(2875 2000);
DISPLAY 0.872340 (2875 2000);
PAINT GREEN (2875 2000);
DISPLAY INVISIBLE (2875 2000);
FORCEPROP 2 LAST PATH I146
J 0
(3200 2150);
DISPLAY 1.021277 (3200 2150);
PAINT ORANGE (3200 2150);
DISPLAY INVISIBLE (3200 2150);
FORCEADD TAP..1
(1550 2750);
FORCEPROP 3 LASTPIN (1500 2750) SIG_NAME P3E_CPU0_PE3_OCP_RXP<1>
J 0
(1510 2760);
DISPLAY 0.659574 (1510 2760);
PAINT MONO (1510 2760);
DISPLAY INVISIBLE (1510 2760);
FORCEPROP 1 LASTPIN (1500 2750) BN 1
J 0
(1488 2758);
DISPLAY 0.617021 (1488 2758);
PAINT GREEN (1488 2758);
FORCEPROP 2 LAST CDS_LIB mstr_standard
J 0
(1550 2750);
PAINT ORANGE (1550 2750);
DISPLAY INVISIBLE (1550 2750);
FORCEPROP 1 LAST BODY_TYPE PLUMBING
J 0
(1550 2800);
DISPLAY 0.872340 (1550 2800);
PAINT GREEN (1550 2800);
DISPLAY INVISIBLE (1550 2800);
FORCEPROP 1 LAST HDL_TAP TRUE
J 0
(1875 2625);
DISPLAY 0.872340 (1875 2625);
PAINT ORANGE (1875 2625);
DISPLAY INVISIBLE (1875 2625);
FORCEPROP 1 LAST PATH I147
J 0
(1548 2750);
DISPLAY 0.872340 (1548 2750);
PAINT GREEN (1548 2750);
DISPLAY INVISIBLE (1548 2750);
FORCEADD TAP..1
(1750 2500);
FORCEPROP 3 LASTPIN (1700 2500) SIG_NAME P3E_CPU0_PE3_OCP_RXN<0>
J 0
(1710 2510);
DISPLAY 0.659574 (1710 2510);
PAINT MONO (1710 2510);
DISPLAY INVISIBLE (1710 2510);
FORCEPROP 1 LASTPIN (1700 2500) BN 0
J 0
(1688 2508);
DISPLAY 0.617021 (1688 2508);
PAINT GREEN (1688 2508);
FORCEPROP 2 LAST CDS_LIB mstr_standard
J 0
(1750 2500);
PAINT ORANGE (1750 2500);
DISPLAY INVISIBLE (1750 2500);
FORCEPROP 1 LAST BODY_TYPE PLUMBING
J 0
(1750 2550);
DISPLAY 0.872340 (1750 2550);
PAINT GREEN (1750 2550);
DISPLAY INVISIBLE (1750 2550);
FORCEPROP 1 LAST HDL_TAP TRUE
J 0
(2075 2375);
DISPLAY 0.872340 (2075 2375);
PAINT ORANGE (2075 2375);
DISPLAY INVISIBLE (2075 2375);
FORCEPROP 1 LAST PATH I148
J 0
(1748 2500);
DISPLAY 0.872340 (1748 2500);
PAINT GREEN (1748 2500);
DISPLAY INVISIBLE (1748 2500);
FORCEADD TAP..1
(1550 2550);
FORCEPROP 3 LASTPIN (1500 2550) SIG_NAME P3E_CPU0_PE3_OCP_RXP<0>
J 0
(1510 2560);
DISPLAY 0.659574 (1510 2560);
PAINT MONO (1510 2560);
DISPLAY INVISIBLE (1510 2560);
FORCEPROP 1 LASTPIN (1500 2550) BN 0
J 0
(1488 2558);
DISPLAY 0.617021 (1488 2558);
PAINT GREEN (1488 2558);
FORCEPROP 2 LAST CDS_LIB mstr_standard
J 0
(1550 2550);
PAINT ORANGE (1550 2550);
DISPLAY INVISIBLE (1550 2550);
FORCEPROP 1 LAST BODY_TYPE PLUMBING
J 0
(1550 2600);
DISPLAY 0.872340 (1550 2600);
PAINT GREEN (1550 2600);
DISPLAY INVISIBLE (1550 2600);
FORCEPROP 1 LAST HDL_TAP TRUE
J 0
(1875 2425);
DISPLAY 0.872340 (1875 2425);
PAINT ORANGE (1875 2425);
DISPLAY INVISIBLE (1875 2425);
FORCEPROP 1 LAST PATH I149
J 0
(1548 2550);
DISPLAY 0.872340 (1548 2550);
PAINT GREEN (1548 2550);
DISPLAY INVISIBLE (1548 2550);
FORCEADD RES..1
(1725 2150);
FORCEPROP 1 LAST LOCATION R9E11
J 0
(1675 2200);
DISPLAY 0.617021 (1675 2200);
PAINT AQUA (1675 2200);
FORCEPROP 1 LAST PART_NUMBER G21796-004
J 0
(1550 2100);
DISPLAY 0.617021 (1550 2100);
PAINT BLUE (1550 2100);
FORCEPROP 1 LAST VALUE 200.0
J 2
(1700 2050);
DISPLAY 0.617021 (1700 2050);
PAINT SKYBLUE (1700 2050);
FORCEPROP 1 LAST TOLERANCE 1%
J 0
(1725 2050);
DISPLAY 0.617021 (1725 2050);
PAINT SKYBLUE (1725 2050);
FORCEPROP 1 LAST PACK_TYPE 0402
J 0
(1825 2075);
DISPLAY 0.617021 (1825 2075);
PAINT SKYBLUE (1825 2075);
FORCEPROP 1 LAST MATERIAL CHIP
J 0
(1725 2000);
DISPLAY 0.617021 (1725 2000);
PAINT SKYBLUE (1725 2000);
FORCEPROP 1 LAST WATTAGE 1/16W
J 2
(1700 2000);
DISPLAY 0.617021 (1700 2000);
PAINT SKYBLUE (1700 2000);
FORCEPROP 1 LASTPIN (1825 2150) $PN 2
J 0
(1787 2162);
DISPLAY 0.617021 (1787 2162);
PAINT ORANGE (1787 2162);
FORCEPROP 1 LASTPIN (1625 2150) $PN 1
J 0
(1637 2162);
DISPLAY 0.617021 (1637 2162);
PAINT ORANGE (1637 2162);
FORCEPROP 2 LAST CDS_LIB mstr_discrete
J 0
(1725 2150);
PAINT ORANGE (1725 2150);
DISPLAY INVISIBLE (1725 2150);
FORCEPROP 2 LAST SEC_TYPE 0402
J 0
(1675 2350);
DISPLAY 1.021277 (1675 2350);
PAINT ORANGE (1675 2350);
DISPLAY INVISIBLE (1675 2350);
FORCEPROP 2 LAST SEC 1
J 0
(1675 2350);
DISPLAY 0.680851 (1675 2350);
PAINT MONO (1675 2350);
DISPLAY INVISIBLE (1675 2350);
FORCEPROP 2 LAST CDS_LOCATION R9E11
J 0
(1675 2200);
DISPLAY 0.617021 (1675 2200);
PAINT AQUA (1675 2200);
DISPLAY INVISIBLE (1675 2200);
FORCEPROP 1 LAST PATH I150
J 0
(1675 2300);
DISPLAY 0.978723 (1675 2300);
PAINT WHITE (1675 2300);
DISPLAY INVISIBLE (1675 2300);
FORCEPROP 0 LAST ROOM IO_SLOT
J 0
(1675 2350);
DISPLAY 1.021277 (1675 2350);
PAINT ORANGE (1675 2350);
DISPLAY INVISIBLE (1675 2350);
FORCEADD OFFPAGE..1
R 2
(1600 2350);
FORCEPROP 2 LAST $XR0 114 
J 0
(1786 2350);
DISPLAY 0.638298 (1786 2350);
PAINT MONO (1786 2350);
FORCEPROP 2 LAST CDS_LIB mstr_standard
J 2
(1600 2350);
PAINT ORANGE (1600 2350);
DISPLAY INVISIBLE (1600 2350);
FORCEPROP 1 LAST OFFPAGE TRUE
J 2
(1275 2225);
DISPLAY 0.872340 (1275 2225);
PAINT GREEN (1275 2225);
DISPLAY INVISIBLE (1275 2225);
FORCEPROP 1 LAST COMMENT_BODY TRUE
J 2
(1475 2250);
DISPLAY 0.872340 (1475 2250);
PAINT GREEN (1475 2250);
DISPLAY INVISIBLE (1475 2250);
FORCEPROP 2 LAST PATH I151
J 0
(1800 2400);
DISPLAY 1.021277 (1800 2400);
PAINT ORANGE (1800 2400);
DISPLAY INVISIBLE (1800 2400);
FORCEADD OFFPAGE..1
R 2
(1600 2300);
FORCEPROP 2 LAST $XR0 114 
J 0
(1786 2300);
DISPLAY 0.638298 (1786 2300);
PAINT MONO (1786 2300);
FORCEPROP 2 LAST CDS_LIB mstr_standard
J 0
(1600 2300);
PAINT ORANGE (1600 2300);
DISPLAY INVISIBLE (1600 2300);
FORCEPROP 1 LAST OFFPAGE TRUE
J 2
(1275 2175);
DISPLAY 0.872340 (1275 2175);
PAINT GREEN (1275 2175);
DISPLAY INVISIBLE (1275 2175);
FORCEPROP 1 LAST COMMENT_BODY TRUE
J 2
(1475 2200);
DISPLAY 0.872340 (1475 2200);
PAINT GREEN (1475 2200);
DISPLAY INVISIBLE (1475 2200);
FORCEPROP 2 LAST PATH I152
J 0
(1800 2350);
DISPLAY 1.021277 (1800 2350);
PAINT ORANGE (1800 2350);
DISPLAY INVISIBLE (1800 2350);
FORCEADD RES..1
(1275 2100);
FORCEPROP 1 LAST LOCATION R9E12
J 0
(1225 2150);
DISPLAY 0.617021 (1225 2150);
PAINT AQUA (1225 2150);
FORCEPROP 1 LAST PART_NUMBER G21796-004
J 0
(1100 2050);
DISPLAY 0.617021 (1100 2050);
PAINT BLUE (1100 2050);
FORCEPROP 1 LAST VALUE 200.0
J 2
(1250 2000);
DISPLAY 0.617021 (1250 2000);
PAINT SKYBLUE (1250 2000);
FORCEPROP 1 LAST TOLERANCE 1%
J 0
(1275 2000);
DISPLAY 0.617021 (1275 2000);
PAINT SKYBLUE (1275 2000);
FORCEPROP 1 LAST PACK_TYPE 0402
J 0
(1375 2025);
DISPLAY 0.617021 (1375 2025);
PAINT SKYBLUE (1375 2025);
FORCEPROP 1 LAST MATERIAL CHIP
J 0
(1275 1950);
DISPLAY 0.617021 (1275 1950);
PAINT SKYBLUE (1275 1950);
FORCEPROP 1 LAST WATTAGE 1/16W
J 2
(1250 1950);
DISPLAY 0.617021 (1250 1950);
PAINT SKYBLUE (1250 1950);
FORCEPROP 1 LASTPIN (1375 2100) $PN 2
J 0
(1337 2112);
DISPLAY 0.617021 (1337 2112);
PAINT ORANGE (1337 2112);
FORCEPROP 1 LASTPIN (1175 2100) $PN 1
J 0
(1187 2112);
DISPLAY 0.617021 (1187 2112);
PAINT ORANGE (1187 2112);
FORCEPROP 2 LAST CDS_LIB mstr_discrete
J 0
(1275 2100);
PAINT ORANGE (1275 2100);
DISPLAY INVISIBLE (1275 2100);
FORCEPROP 2 LAST SEC_TYPE 0402
J 0
(1225 2300);
DISPLAY 1.021277 (1225 2300);
PAINT ORANGE (1225 2300);
DISPLAY INVISIBLE (1225 2300);
FORCEPROP 2 LAST SEC 1
J 0
(1225 2300);
DISPLAY 0.680851 (1225 2300);
PAINT MONO (1225 2300);
DISPLAY INVISIBLE (1225 2300);
FORCEPROP 2 LAST CDS_LOCATION R9E12
J 0
(1225 2150);
DISPLAY 0.617021 (1225 2150);
PAINT AQUA (1225 2150);
DISPLAY INVISIBLE (1225 2150);
FORCEPROP 1 LAST PATH I153
J 0
(1225 2250);
DISPLAY 0.978723 (1225 2250);
PAINT WHITE (1225 2250);
DISPLAY INVISIBLE (1225 2250);
FORCEPROP 0 LAST ROOM IO_SLOT
J 0
(1225 2300);
DISPLAY 1.021277 (1225 2300);
PAINT ORANGE (1225 2300);
DISPLAY INVISIBLE (1225 2300);
FORCEADD GND..1
(625 1900);
FORCEPROP 3 LASTPIN (625 1950) SIG_NAME GND\g
J 0
(635 1960);
DISPLAY 0.659574 (635 1960);
PAINT MONO (635 1960);
DISPLAY INVISIBLE (635 1960);
FORCEPROP 1 LAST VOLTAGE 0
J 0
(625 1900);
PAINT SKYBLUE (625 1900);
DISPLAY INVISIBLE (625 1900);
FORCEPROP 2 LAST CDS_LIB mstr_symbols
J 0
(625 1900);
PAINT ORANGE (625 1900);
DISPLAY INVISIBLE (625 1900);
FORCEPROP 1 LAST SIZE 1B
J 0
(700 1850);
DISPLAY 0.872340 (700 1850);
PAINT AQUA (700 1850);
DISPLAY INVISIBLE (700 1850);
FORCEPROP 1 LAST BODY_TYPE PLUMBING
J 0
(580 1857);
DISPLAY 0.340426 (580 1857);
PAINT GREEN (580 1857);
DISPLAY INVISIBLE (580 1857);
FORCEPROP 1 LAST PATH I154
J 0
(700 1900);
DISPLAY 0.872340 (700 1900);
PAINT AQUA (700 1900);
DISPLAY INVISIBLE (700 1900);
FORCEPROP 1 LAST HDL_POWER GND
J 0
(625 2050);
DISPLAY 0.872340 (625 2050);
PAINT GREEN (625 2050);
DISPLAY INVISIBLE (625 2050);
FORCEADD TAP..1
R 2
(-1675 3050);
FORCEPROP 3 LASTPIN (-1625 3050) SIG_NAME P3E_OCP_CPU0_PE3_C_TXP<3>
J 0
(-1615 3060);
DISPLAY 0.659574 (-1615 3060);
PAINT MONO (-1615 3060);
DISPLAY INVISIBLE (-1615 3060);
FORCEPROP 1 LASTPIN (-1625 3050) BN 3
J 2
(-1613 3058);
DISPLAY 0.617021 (-1613 3058);
PAINT GREEN (-1613 3058);
FORCEPROP 2 LAST CDS_LIB mstr_standard
J 0
(-1675 3050);
PAINT ORANGE (-1675 3050);
DISPLAY INVISIBLE (-1675 3050);
FORCEPROP 1 LAST BODY_TYPE PLUMBING
J 2
(-1675 3100);
DISPLAY 0.872340 (-1675 3100);
PAINT GREEN (-1675 3100);
DISPLAY INVISIBLE (-1675 3100);
FORCEPROP 1 LAST HDL_TAP TRUE
J 2
(-2000 2925);
DISPLAY 0.872340 (-2000 2925);
PAINT ORANGE (-2000 2925);
DISPLAY INVISIBLE (-2000 2925);
FORCEPROP 1 LAST PATH I155
J 2
(-1673 3050);
DISPLAY 0.872340 (-1673 3050);
PAINT GREEN (-1673 3050);
DISPLAY INVISIBLE (-1673 3050);
FORCEADD TAP..1
R 2
(-1675 2650);
FORCEPROP 3 LASTPIN (-1625 2650) SIG_NAME P3E_OCP_CPU0_PE3_C_TXP<1>
J 0
(-1615 2660);
DISPLAY 0.659574 (-1615 2660);
PAINT MONO (-1615 2660);
DISPLAY INVISIBLE (-1615 2660);
FORCEPROP 1 LASTPIN (-1625 2650) BN 1
J 2
(-1613 2658);
DISPLAY 0.617021 (-1613 2658);
PAINT GREEN (-1613 2658);
FORCEPROP 2 LAST CDS_LIB mstr_standard
J 0
(-1675 2650);
PAINT ORANGE (-1675 2650);
DISPLAY INVISIBLE (-1675 2650);
FORCEPROP 1 LAST BODY_TYPE PLUMBING
J 2
(-1675 2700);
DISPLAY 0.872340 (-1675 2700);
PAINT GREEN (-1675 2700);
DISPLAY INVISIBLE (-1675 2700);
FORCEPROP 1 LAST HDL_TAP TRUE
J 2
(-2000 2525);
DISPLAY 0.872340 (-2000 2525);
PAINT ORANGE (-2000 2525);
DISPLAY INVISIBLE (-2000 2525);
FORCEPROP 1 LAST PATH I156
J 2
(-1673 2650);
DISPLAY 0.872340 (-1673 2650);
PAINT GREEN (-1673 2650);
DISPLAY INVISIBLE (-1673 2650);
FORCEADD TAP..1
R 2
(-1675 2850);
FORCEPROP 3 LASTPIN (-1625 2850) SIG_NAME P3E_OCP_CPU0_PE3_C_TXP<2>
J 0
(-1615 2860);
DISPLAY 0.659574 (-1615 2860);
PAINT MONO (-1615 2860);
DISPLAY INVISIBLE (-1615 2860);
FORCEPROP 1 LASTPIN (-1625 2850) BN 2
J 2
(-1613 2858);
DISPLAY 0.617021 (-1613 2858);
PAINT GREEN (-1613 2858);
FORCEPROP 2 LAST CDS_LIB mstr_standard
J 0
(-1675 2850);
PAINT ORANGE (-1675 2850);
DISPLAY INVISIBLE (-1675 2850);
FORCEPROP 1 LAST BODY_TYPE PLUMBING
J 2
(-1675 2900);
DISPLAY 0.872340 (-1675 2900);
PAINT GREEN (-1675 2900);
DISPLAY INVISIBLE (-1675 2900);
FORCEPROP 1 LAST HDL_TAP TRUE
J 2
(-2000 2725);
DISPLAY 0.872340 (-2000 2725);
PAINT ORANGE (-2000 2725);
DISPLAY INVISIBLE (-2000 2725);
FORCEPROP 1 LAST PATH I157
J 2
(-1673 2850);
DISPLAY 0.872340 (-1673 2850);
PAINT GREEN (-1673 2850);
DISPLAY INVISIBLE (-1673 2850);
FORCEADD TAP..1
R 2
(-1675 2450);
FORCEPROP 3 LASTPIN (-1625 2450) SIG_NAME P3E_OCP_CPU0_PE3_C_TXP<0>
J 0
(-1615 2460);
DISPLAY 0.659574 (-1615 2460);
PAINT MONO (-1615 2460);
DISPLAY INVISIBLE (-1615 2460);
FORCEPROP 1 LASTPIN (-1625 2450) BN 0
J 2
(-1613 2458);
DISPLAY 0.617021 (-1613 2458);
PAINT GREEN (-1613 2458);
FORCEPROP 2 LAST CDS_LIB mstr_standard
J 0
(-1675 2450);
PAINT ORANGE (-1675 2450);
DISPLAY INVISIBLE (-1675 2450);
FORCEPROP 1 LAST BODY_TYPE PLUMBING
J 2
(-1675 2500);
DISPLAY 0.872340 (-1675 2500);
PAINT GREEN (-1675 2500);
DISPLAY INVISIBLE (-1675 2500);
FORCEPROP 1 LAST HDL_TAP TRUE
J 2
(-2000 2325);
DISPLAY 0.872340 (-2000 2325);
PAINT ORANGE (-2000 2325);
DISPLAY INVISIBLE (-2000 2325);
FORCEPROP 1 LAST PATH I158
J 2
(-1673 2450);
DISPLAY 0.872340 (-1673 2450);
PAINT GREEN (-1673 2450);
DISPLAY INVISIBLE (-1673 2450);
FORCEADD OFFPAGE..1
(-1700 2200);
FORCEPROP 2 LAST $XR0 114 
J 0
(-2012 2200);
DISPLAY 0.638298 (-2012 2200);
PAINT MONO (-2012 2200);
FORCEPROP 2 LAST CDS_LIB mstr_standard
J 0
(-1700 2200);
PAINT ORANGE (-1700 2200);
DISPLAY INVISIBLE (-1700 2200);
FORCEPROP 1 LAST OFFPAGE TRUE
J 0
(-1375 2075);
DISPLAY 0.872340 (-1375 2075);
PAINT GREEN (-1375 2075);
DISPLAY INVISIBLE (-1375 2075);
FORCEPROP 1 LAST COMMENT_BODY TRUE
J 0
(-1575 2100);
DISPLAY 0.872340 (-1575 2100);
PAINT GREEN (-1575 2100);
DISPLAY INVISIBLE (-1575 2100);
FORCEPROP 2 LAST PATH I159
J 0
(-2000 2250);
DISPLAY 1.021277 (-2000 2250);
PAINT ORANGE (-2000 2250);
DISPLAY INVISIBLE (-2000 2250);
FORCEADD OFFPAGE..1
(-1700 2250);
FORCEPROP 2 LAST $XR0 114 
J 0
(-2012 2250);
DISPLAY 0.638298 (-2012 2250);
PAINT MONO (-2012 2250);
FORCEPROP 2 LAST CDS_LIB mstr_standard
J 0
(-1700 2250);
PAINT ORANGE (-1700 2250);
DISPLAY INVISIBLE (-1700 2250);
FORCEPROP 1 LAST OFFPAGE TRUE
J 0
(-1375 2125);
DISPLAY 0.872340 (-1375 2125);
PAINT GREEN (-1375 2125);
DISPLAY INVISIBLE (-1375 2125);
FORCEPROP 1 LAST COMMENT_BODY TRUE
J 0
(-1575 2150);
DISPLAY 0.872340 (-1575 2150);
PAINT GREEN (-1575 2150);
DISPLAY INVISIBLE (-1575 2150);
FORCEPROP 2 LAST PATH I160
J 0
(-2000 2300);
DISPLAY 1.021277 (-2000 2300);
PAINT ORANGE (-2000 2300);
DISPLAY INVISIBLE (-2000 2300);
FORCEADD GND..1
(-725 1850);
FORCEPROP 3 LASTPIN (-725 1900) SIG_NAME GND\g
J 0
(-715 1910);
DISPLAY 0.659574 (-715 1910);
PAINT MONO (-715 1910);
DISPLAY INVISIBLE (-715 1910);
FORCEPROP 1 LAST VOLTAGE 0
J 0
(-725 1850);
PAINT SKYBLUE (-725 1850);
DISPLAY INVISIBLE (-725 1850);
FORCEPROP 2 LAST CDS_LIB mstr_symbols
J 0
(-725 1850);
PAINT ORANGE (-725 1850);
DISPLAY INVISIBLE (-725 1850);
FORCEPROP 1 LAST SIZE 1B
J 0
(-650 1800);
DISPLAY 0.872340 (-650 1800);
PAINT AQUA (-650 1800);
DISPLAY INVISIBLE (-650 1800);
FORCEPROP 1 LAST BODY_TYPE PLUMBING
J 0
(-770 1807);
DISPLAY 0.340426 (-770 1807);
PAINT GREEN (-770 1807);
DISPLAY INVISIBLE (-770 1807);
FORCEPROP 1 LAST PATH I162
J 0
(-650 1850);
DISPLAY 0.872340 (-650 1850);
PAINT AQUA (-650 1850);
DISPLAY INVISIBLE (-650 1850);
FORCEPROP 1 LAST HDL_POWER GND
J 0
(-725 2000);
DISPLAY 0.872340 (-725 2000);
PAINT GREEN (-725 2000);
DISPLAY INVISIBLE (-725 2000);
FORCEADD TAP..1
R 2
(-1950 2600);
FORCEPROP 3 LASTPIN (-1900 2600) SIG_NAME P3E_OCP_CPU0_PE3_C_TXN<1>
J 0
(-1890 2610);
DISPLAY 0.659574 (-1890 2610);
PAINT MONO (-1890 2610);
DISPLAY INVISIBLE (-1890 2610);
FORCEPROP 1 LASTPIN (-1900 2600) BN 1
J 2
(-1888 2608);
DISPLAY 0.617021 (-1888 2608);
PAINT GREEN (-1888 2608);
FORCEPROP 2 LAST CDS_LIB mstr_standard
J 0
(-1950 2600);
PAINT ORANGE (-1950 2600);
DISPLAY INVISIBLE (-1950 2600);
FORCEPROP 1 LAST BODY_TYPE PLUMBING
J 2
(-1950 2650);
DISPLAY 0.872340 (-1950 2650);
PAINT GREEN (-1950 2650);
DISPLAY INVISIBLE (-1950 2650);
FORCEPROP 1 LAST HDL_TAP TRUE
J 2
(-2275 2475);
DISPLAY 0.872340 (-2275 2475);
PAINT ORANGE (-2275 2475);
DISPLAY INVISIBLE (-2275 2475);
FORCEPROP 1 LAST PATH I164
J 2
(-1948 2600);
DISPLAY 0.872340 (-1948 2600);
PAINT GREEN (-1948 2600);
DISPLAY INVISIBLE (-1948 2600);
FORCEADD TAP..1
R 2
(-1950 2800);
FORCEPROP 3 LASTPIN (-1900 2800) SIG_NAME P3E_OCP_CPU0_PE3_C_TXN<2>
J 0
(-1890 2810);
DISPLAY 0.659574 (-1890 2810);
PAINT MONO (-1890 2810);
DISPLAY INVISIBLE (-1890 2810);
FORCEPROP 1 LASTPIN (-1900 2800) BN 2
J 2
(-1888 2808);
DISPLAY 0.617021 (-1888 2808);
PAINT GREEN (-1888 2808);
FORCEPROP 2 LAST CDS_LIB mstr_standard
J 0
(-1950 2800);
PAINT ORANGE (-1950 2800);
DISPLAY INVISIBLE (-1950 2800);
FORCEPROP 1 LAST BODY_TYPE PLUMBING
J 2
(-1950 2850);
DISPLAY 0.872340 (-1950 2850);
PAINT GREEN (-1950 2850);
DISPLAY INVISIBLE (-1950 2850);
FORCEPROP 1 LAST HDL_TAP TRUE
J 2
(-2275 2675);
DISPLAY 0.872340 (-2275 2675);
PAINT ORANGE (-2275 2675);
DISPLAY INVISIBLE (-2275 2675);
FORCEPROP 1 LAST PATH I165
J 2
(-1948 2800);
DISPLAY 0.872340 (-1948 2800);
PAINT GREEN (-1948 2800);
DISPLAY INVISIBLE (-1948 2800);
FORCEADD TAP..1
R 2
(-1950 3000);
FORCEPROP 3 LASTPIN (-1900 3000) SIG_NAME P3E_OCP_CPU0_PE3_C_TXN<3>
J 0
(-1890 3010);
DISPLAY 0.659574 (-1890 3010);
PAINT MONO (-1890 3010);
DISPLAY INVISIBLE (-1890 3010);
FORCEPROP 1 LASTPIN (-1900 3000) BN 3
J 2
(-1888 3008);
DISPLAY 0.617021 (-1888 3008);
PAINT GREEN (-1888 3008);
FORCEPROP 2 LAST CDS_LIB mstr_standard
J 0
(-1950 3000);
PAINT ORANGE (-1950 3000);
DISPLAY INVISIBLE (-1950 3000);
FORCEPROP 1 LAST BODY_TYPE PLUMBING
J 2
(-1950 3050);
DISPLAY 0.872340 (-1950 3050);
PAINT GREEN (-1950 3050);
DISPLAY INVISIBLE (-1950 3050);
FORCEPROP 1 LAST HDL_TAP TRUE
J 2
(-2275 2875);
DISPLAY 0.872340 (-2275 2875);
PAINT ORANGE (-2275 2875);
DISPLAY INVISIBLE (-2275 2875);
FORCEPROP 1 LAST PATH I166
J 2
(-1948 3000);
DISPLAY 0.872340 (-1948 3000);
PAINT GREEN (-1948 3000);
DISPLAY INVISIBLE (-1948 3000);
FORCEADD TAP..1
R 2
(-1950 2400);
FORCEPROP 3 LASTPIN (-1900 2400) SIG_NAME P3E_OCP_CPU0_PE3_C_TXN<0>
J 0
(-1890 2410);
DISPLAY 0.659574 (-1890 2410);
PAINT MONO (-1890 2410);
DISPLAY INVISIBLE (-1890 2410);
FORCEPROP 1 LASTPIN (-1900 2400) BN 0
J 2
(-1888 2408);
DISPLAY 0.617021 (-1888 2408);
PAINT GREEN (-1888 2408);
FORCEPROP 2 LAST CDS_LIB mstr_standard
J 0
(-1950 2400);
PAINT ORANGE (-1950 2400);
DISPLAY INVISIBLE (-1950 2400);
FORCEPROP 1 LAST BODY_TYPE PLUMBING
J 2
(-1950 2450);
DISPLAY 0.872340 (-1950 2450);
PAINT GREEN (-1950 2450);
DISPLAY INVISIBLE (-1950 2450);
FORCEPROP 1 LAST HDL_TAP TRUE
J 2
(-2275 2275);
DISPLAY 0.872340 (-2275 2275);
PAINT ORANGE (-2275 2275);
DISPLAY INVISIBLE (-2275 2275);
FORCEPROP 1 LAST PATH I167
J 2
(-1948 2400);
DISPLAY 0.872340 (-1948 2400);
PAINT GREEN (-1948 2400);
DISPLAY INVISIBLE (-1948 2400);
FORCEADD OFFPAGE..5
(-1700 2100);
FORCEPROP 2 LAST $XR2 145 
J 0
(-2165 2100);
DISPLAY 0.638298 (-2165 2100);
PAINT MONO (-2165 2100);
FORCEPROP 2 LAST $XR0 133 
J 0
(-2045 2100);
DISPLAY 0.638298 (-2045 2100);
PAINT MONO (-2045 2100);
FORCEPROP 2 LAST $XR1 121 
J 0
(-2165 2100);
DISPLAY 0.638298 (-2165 2100);
PAINT MONO (-2165 2100);
FORCEPROP 2 LAST CDS_LIB mstr_standard
J 0
(-1700 2100);
PAINT ORANGE (-1700 2100);
DISPLAY INVISIBLE (-1700 2100);
FORCEPROP 1 LAST OFFPAGE TRUE
J 0
(-1375 1975);
DISPLAY 0.872340 (-1375 1975);
PAINT GREEN (-1375 1975);
DISPLAY INVISIBLE (-1375 1975);
FORCEPROP 1 LAST COMMENT_BODY TRUE
J 0
(-1600 2025);
DISPLAY 0.872340 (-1600 2025);
PAINT GREEN (-1600 2025);
DISPLAY INVISIBLE (-1600 2025);
FORCEPROP 2 LAST PATH I168
J 0
(-1650 2175);
DISPLAY 1.021277 (-1650 2175);
PAINT ORANGE (-1650 2175);
DISPLAY INVISIBLE (-1650 2175);
FORCEADD RES..1
(975 4050);
FORCEPROP 1 LAST LOCATION R2R8
J 0
(925 4100);
DISPLAY 0.617021 (925 4100);
PAINT AQUA (925 4100);
FORCEPROP 1 LAST PART_NUMBER G21796-017
J 0
(925 4150);
DISPLAY 0.617021 (925 4150);
PAINT BLUE (925 4150);
FORCEPROP 1 LAST VALUE 100.0
J 2
(950 3950);
DISPLAY 0.617021 (950 3950);
PAINT SKYBLUE (950 3950);
FORCEPROP 1 LAST TOLERANCE 1%
J 0
(975 3950);
DISPLAY 0.617021 (975 3950);
PAINT SKYBLUE (975 3950);
FORCEPROP 1 LAST PACK_TYPE 0402
J 0
(1225 3900);
DISPLAY 0.617021 (1225 3900);
PAINT SKYBLUE (1225 3900);
FORCEPROP 1 LAST MATERIAL CHIP
J 0
(975 3900);
DISPLAY 0.617021 (975 3900);
PAINT SKYBLUE (975 3900);
FORCEPROP 1 LAST WATTAGE 1/16W
J 2
(950 3900);
DISPLAY 0.617021 (950 3900);
PAINT SKYBLUE (950 3900);
FORCEPROP 1 LASTPIN (1075 4050) $PN 2
J 0
(1037 4062);
DISPLAY 0.617021 (1037 4062);
PAINT ORANGE (1037 4062);
FORCEPROP 1 LASTPIN (875 4050) $PN 1
J 0
(887 4062);
DISPLAY 0.617021 (887 4062);
PAINT ORANGE (887 4062);
FORCEPROP 2 LAST CDS_LIB mstr_discrete
J 0
(975 4050);
PAINT ORANGE (975 4050);
DISPLAY INVISIBLE (975 4050);
FORCEPROP 2 LAST SEC_TYPE 0402
J 0
(925 4250);
DISPLAY 1.021277 (925 4250);
PAINT ORANGE (925 4250);
DISPLAY INVISIBLE (925 4250);
FORCEPROP 2 LAST SEC 1
J 0
(925 4250);
DISPLAY 0.680851 (925 4250);
PAINT MONO (925 4250);
DISPLAY INVISIBLE (925 4250);
FORCEPROP 2 LAST CDS_LOCATION R2R8
J 0
(925 4100);
DISPLAY 0.617021 (925 4100);
PAINT AQUA (925 4100);
DISPLAY INVISIBLE (925 4100);
FORCEPROP 1 LAST PATH I18
J 0
(925 4200);
DISPLAY 0.978723 (925 4200);
PAINT WHITE (925 4200);
DISPLAY INVISIBLE (925 4200);
FORCEPROP 0 LAST ROOM IO_SLOT
J 0
(925 4250);
DISPLAY 1.021277 (925 4250);
PAINT ORANGE (925 4250);
DISPLAY INVISIBLE (925 4250);
FORCEADD GND..1
(1325 4000);
FORCEPROP 3 LASTPIN (1325 4050) SIG_NAME GND\g
J 0
(1335 4060);
DISPLAY 0.659574 (1335 4060);
PAINT MONO (1335 4060);
DISPLAY INVISIBLE (1335 4060);
FORCEPROP 1 LAST VOLTAGE 0
J 0
(1325 4000);
PAINT SKYBLUE (1325 4000);
DISPLAY INVISIBLE (1325 4000);
FORCEPROP 2 LAST CDS_LIB mstr_symbols
J 0
(1325 4000);
PAINT ORANGE (1325 4000);
DISPLAY INVISIBLE (1325 4000);
FORCEPROP 1 LAST SIZE 1B
J 0
(1400 3950);
DISPLAY 0.872340 (1400 3950);
PAINT AQUA (1400 3950);
DISPLAY INVISIBLE (1400 3950);
FORCEPROP 1 LAST BODY_TYPE PLUMBING
J 0
(1280 3957);
DISPLAY 0.340426 (1280 3957);
PAINT GREEN (1280 3957);
DISPLAY INVISIBLE (1280 3957);
FORCEPROP 1 LAST PATH I19
J 0
(1400 4000);
DISPLAY 0.872340 (1400 4000);
PAINT AQUA (1400 4000);
DISPLAY INVISIBLE (1400 4000);
FORCEPROP 1 LAST HDL_POWER GND
J 0
(1325 4150);
DISPLAY 0.872340 (1325 4150);
PAINT GREEN (1325 4150);
DISPLAY INVISIBLE (1325 4150);
FORCEADD OFFPAGE..2
(2525 3950);
FORCEPROP 2 LAST $XR0 32 
J 0
(2714 3950);
DISPLAY 0.638298 (2714 3950);
PAINT MONO (2714 3950);
FORCEPROP 2 LAST CDS_LIB mstr_standard
J 0
(2525 3950);
PAINT ORANGE (2525 3950);
DISPLAY INVISIBLE (2525 3950);
FORCEPROP 1 LAST OFFPAGE TRUE
J 0
(2850 3825);
DISPLAY 0.872340 (2850 3825);
PAINT GREEN (2850 3825);
DISPLAY INVISIBLE (2850 3825);
FORCEPROP 1 LAST COMMENT_BODY TRUE
J 0
(2480 3855);
DISPLAY 0.872340 (2480 3855);
PAINT GREEN (2480 3855);
DISPLAY INVISIBLE (2480 3855);
FORCEPROP 2 LAST PATH I44
J 2
(2325 4000);
DISPLAY 1.021277 (2325 4000);
PAINT ORANGE (2325 4000);
DISPLAY INVISIBLE (2325 4000);
FORCEADD OFFPAGE..2
(2525 4025);
FORCEPROP 2 LAST $XR0 32 
J 0
(2714 4025);
DISPLAY 0.638298 (2714 4025);
PAINT MONO (2714 4025);
FORCEPROP 2 LAST CDS_LIB mstr_standard
J 0
(2525 4025);
PAINT ORANGE (2525 4025);
DISPLAY INVISIBLE (2525 4025);
FORCEPROP 1 LAST OFFPAGE TRUE
J 0
(2850 3900);
DISPLAY 0.872340 (2850 3900);
PAINT GREEN (2850 3900);
DISPLAY INVISIBLE (2850 3900);
FORCEPROP 1 LAST COMMENT_BODY TRUE
J 0
(2480 3930);
DISPLAY 0.872340 (2480 3930);
PAINT GREEN (2480 3930);
DISPLAY INVISIBLE (2480 3930);
FORCEPROP 2 LAST PATH I45
J 2
(2325 4075);
DISPLAY 1.021277 (2325 4075);
PAINT ORANGE (2325 4075);
DISPLAY INVISIBLE (2325 4075);
FORCEADD TAP..1
(1550 3950);
FORCEPROP 3 LASTPIN (1500 3950) SIG_NAME P3E_CPU0_PE3_OCP_RXP<7>
J 0
(1510 3960);
DISPLAY 0.659574 (1510 3960);
PAINT MONO (1510 3960);
DISPLAY INVISIBLE (1510 3960);
FORCEPROP 1 LASTPIN (1500 3950) BN 7
J 0
(1488 3958);
DISPLAY 0.617021 (1488 3958);
PAINT GREEN (1488 3958);
FORCEPROP 2 LAST CDS_LIB mstr_standard
J 0
(1550 3950);
PAINT ORANGE (1550 3950);
DISPLAY INVISIBLE (1550 3950);
FORCEPROP 1 LAST BODY_TYPE PLUMBING
J 0
(1550 4000);
DISPLAY 0.872340 (1550 4000);
PAINT GREEN (1550 4000);
DISPLAY INVISIBLE (1550 4000);
FORCEPROP 1 LAST HDL_TAP TRUE
J 0
(1875 3825);
DISPLAY 0.872340 (1875 3825);
PAINT ORANGE (1875 3825);
DISPLAY INVISIBLE (1875 3825);
FORCEPROP 1 LAST PATH I46
J 0
(1548 3950);
DISPLAY 0.872340 (1548 3950);
PAINT GREEN (1548 3950);
DISPLAY INVISIBLE (1548 3950);
FORCEADD TAP..1
(1750 3900);
FORCEPROP 3 LASTPIN (1700 3900) SIG_NAME P3E_CPU0_PE3_OCP_RXN<7>
J 0
(1710 3910);
DISPLAY 0.659574 (1710 3910);
PAINT MONO (1710 3910);
DISPLAY INVISIBLE (1710 3910);
FORCEPROP 1 LASTPIN (1700 3900) BN 7
J 0
(1688 3908);
DISPLAY 0.617021 (1688 3908);
PAINT GREEN (1688 3908);
FORCEPROP 2 LAST CDS_LIB mstr_standard
J 0
(1750 3900);
PAINT ORANGE (1750 3900);
DISPLAY INVISIBLE (1750 3900);
FORCEPROP 1 LAST BODY_TYPE PLUMBING
J 0
(1750 3950);
DISPLAY 0.872340 (1750 3950);
PAINT GREEN (1750 3950);
DISPLAY INVISIBLE (1750 3950);
FORCEPROP 1 LAST HDL_TAP TRUE
J 0
(2075 3775);
DISPLAY 0.872340 (2075 3775);
PAINT ORANGE (2075 3775);
DISPLAY INVISIBLE (2075 3775);
FORCEPROP 1 LAST PATH I47
J 0
(1748 3900);
DISPLAY 0.872340 (1748 3900);
PAINT GREEN (1748 3900);
DISPLAY INVISIBLE (1748 3900);
FORCEADD TAP..1
(1750 3100);
FORCEPROP 3 LASTPIN (1700 3100) SIG_NAME P3E_CPU0_PE3_OCP_RXN<3>
J 0
(1710 3110);
DISPLAY 0.659574 (1710 3110);
PAINT MONO (1710 3110);
DISPLAY INVISIBLE (1710 3110);
FORCEPROP 1 LASTPIN (1700 3100) BN 3
J 0
(1688 3108);
DISPLAY 0.617021 (1688 3108);
PAINT GREEN (1688 3108);
FORCEPROP 2 LAST CDS_LIB mstr_standard
J 0
(1750 3100);
PAINT ORANGE (1750 3100);
DISPLAY INVISIBLE (1750 3100);
FORCEPROP 1 LAST BODY_TYPE PLUMBING
J 0
(1750 3150);
DISPLAY 0.872340 (1750 3150);
PAINT GREEN (1750 3150);
DISPLAY INVISIBLE (1750 3150);
FORCEPROP 1 LAST HDL_TAP TRUE
J 0
(2075 2975);
DISPLAY 0.872340 (2075 2975);
PAINT ORANGE (2075 2975);
DISPLAY INVISIBLE (2075 2975);
FORCEPROP 1 LAST PATH I50
J 0
(1748 3100);
DISPLAY 0.872340 (1748 3100);
PAINT GREEN (1748 3100);
DISPLAY INVISIBLE (1748 3100);
FORCEADD TAP..1
(1550 3150);
FORCEPROP 3 LASTPIN (1500 3150) SIG_NAME P3E_CPU0_PE3_OCP_RXP<3>
J 0
(1510 3160);
DISPLAY 0.659574 (1510 3160);
PAINT MONO (1510 3160);
DISPLAY INVISIBLE (1510 3160);
FORCEPROP 1 LASTPIN (1500 3150) BN 3
J 0
(1488 3158);
DISPLAY 0.617021 (1488 3158);
PAINT GREEN (1488 3158);
FORCEPROP 2 LAST CDS_LIB mstr_standard
J 0
(1550 3150);
PAINT ORANGE (1550 3150);
DISPLAY INVISIBLE (1550 3150);
FORCEPROP 1 LAST BODY_TYPE PLUMBING
J 0
(1550 3200);
DISPLAY 0.872340 (1550 3200);
PAINT GREEN (1550 3200);
DISPLAY INVISIBLE (1550 3200);
FORCEPROP 1 LAST HDL_TAP TRUE
J 0
(1875 3025);
DISPLAY 0.872340 (1875 3025);
PAINT ORANGE (1875 3025);
DISPLAY INVISIBLE (1875 3025);
FORCEPROP 1 LAST PATH I51
J 0
(1548 3150);
DISPLAY 0.872340 (1548 3150);
PAINT GREEN (1548 3150);
DISPLAY INVISIBLE (1548 3150);
FORCEADD P12V_STBY..1
(-1000 4375);
FORCEPROP 3 LASTPIN (-1000 4325) SIG_NAME P12V_STBY\g
J 0
(-990 4335);
DISPLAY 0.659574 (-990 4335);
PAINT MONO (-990 4335);
DISPLAY INVISIBLE (-990 4335);
FORCEPROP 1 LAST VOLTAGE 12.0V
J 0
(-1045 4332);
DISPLAY 0.340426 (-1045 4332);
PAINT SKYBLUE (-1045 4332);
DISPLAY INVISIBLE (-1045 4332);
FORCEPROP 1 LAST SIZE 1B
J 0
(-955 4397);
DISPLAY 0.340426 (-955 4397);
PAINT GREEN (-955 4397);
DISPLAY INVISIBLE (-955 4397);
FORCEPROP 2 LAST CDS_LIB mstr_symbols
J 0
(-1000 4375);
PAINT ORANGE (-1000 4375);
DISPLAY INVISIBLE (-1000 4375);
FORCEPROP 1 LAST BODY_TYPE PLUMBING
J 0
(-1045 4332);
DISPLAY 0.340426 (-1045 4332);
PAINT GREEN (-1045 4332);
DISPLAY INVISIBLE (-1045 4332);
FORCEPROP 1 LAST PATH I70
J 0
(-955 4377);
DISPLAY 0.340426 (-955 4377);
PAINT GREEN (-955 4377);
DISPLAY INVISIBLE (-955 4377);
FORCEPROP 1 LAST HDL_POWER P12V_STBY
J 0
(-1300 4250);
DISPLAY 0.872340 (-1300 4250);
PAINT ORANGE (-1300 4250);
DISPLAY INVISIBLE (-1300 4250);
FORCEADD TAP..1
R 2
(-1675 3850);
FORCEPROP 3 LASTPIN (-1625 3850) SIG_NAME P3E_OCP_CPU0_PE3_C_TXP<7>
J 0
(-1615 3860);
DISPLAY 0.659574 (-1615 3860);
PAINT MONO (-1615 3860);
DISPLAY INVISIBLE (-1615 3860);
FORCEPROP 1 LASTPIN (-1625 3850) BN 7
J 2
(-1613 3858);
DISPLAY 0.617021 (-1613 3858);
PAINT GREEN (-1613 3858);
FORCEPROP 2 LAST CDS_LIB mstr_standard
J 0
(-1675 3850);
PAINT ORANGE (-1675 3850);
DISPLAY INVISIBLE (-1675 3850);
FORCEPROP 1 LAST BODY_TYPE PLUMBING
J 2
(-1675 3900);
DISPLAY 0.872340 (-1675 3900);
PAINT GREEN (-1675 3900);
DISPLAY INVISIBLE (-1675 3900);
FORCEPROP 1 LAST HDL_TAP TRUE
J 2
(-2000 3725);
DISPLAY 0.872340 (-2000 3725);
PAINT ORANGE (-2000 3725);
DISPLAY INVISIBLE (-2000 3725);
FORCEPROP 1 LAST PATH I87
J 2
(-1673 3850);
DISPLAY 0.872340 (-1673 3850);
PAINT GREEN (-1673 3850);
DISPLAY INVISIBLE (-1673 3850);
FORCEADD TAP..1
R 2
(-1675 3650);
FORCEPROP 3 LASTPIN (-1625 3650) SIG_NAME P3E_OCP_CPU0_PE3_C_TXP<6>
J 0
(-1615 3660);
DISPLAY 0.659574 (-1615 3660);
PAINT MONO (-1615 3660);
DISPLAY INVISIBLE (-1615 3660);
FORCEPROP 1 LASTPIN (-1625 3650) BN 6
J 2
(-1613 3658);
DISPLAY 0.617021 (-1613 3658);
PAINT GREEN (-1613 3658);
FORCEPROP 2 LAST CDS_LIB mstr_standard
J 0
(-1675 3650);
PAINT ORANGE (-1675 3650);
DISPLAY INVISIBLE (-1675 3650);
FORCEPROP 1 LAST BODY_TYPE PLUMBING
J 2
(-1675 3700);
DISPLAY 0.872340 (-1675 3700);
PAINT GREEN (-1675 3700);
DISPLAY INVISIBLE (-1675 3700);
FORCEPROP 1 LAST HDL_TAP TRUE
J 2
(-2000 3525);
DISPLAY 0.872340 (-2000 3525);
PAINT ORANGE (-2000 3525);
DISPLAY INVISIBLE (-2000 3525);
FORCEPROP 1 LAST PATH I88
J 2
(-1673 3650);
DISPLAY 0.872340 (-1673 3650);
PAINT GREEN (-1673 3650);
DISPLAY INVISIBLE (-1673 3650);
FORCEADD TAP..1
R 2
(-1675 3450);
FORCEPROP 3 LASTPIN (-1625 3450) SIG_NAME P3E_OCP_CPU0_PE3_C_TXP<5>
J 0
(-1615 3460);
DISPLAY 0.659574 (-1615 3460);
PAINT MONO (-1615 3460);
DISPLAY INVISIBLE (-1615 3460);
FORCEPROP 1 LASTPIN (-1625 3450) BN 5
J 2
(-1613 3458);
DISPLAY 0.617021 (-1613 3458);
PAINT GREEN (-1613 3458);
FORCEPROP 2 LAST CDS_LIB mstr_standard
J 0
(-1675 3450);
PAINT ORANGE (-1675 3450);
DISPLAY INVISIBLE (-1675 3450);
FORCEPROP 1 LAST BODY_TYPE PLUMBING
J 2
(-1675 3500);
DISPLAY 0.872340 (-1675 3500);
PAINT GREEN (-1675 3500);
DISPLAY INVISIBLE (-1675 3500);
FORCEPROP 1 LAST HDL_TAP TRUE
J 2
(-2000 3325);
DISPLAY 0.872340 (-2000 3325);
PAINT ORANGE (-2000 3325);
DISPLAY INVISIBLE (-2000 3325);
FORCEPROP 1 LAST PATH I89
J 2
(-1673 3450);
DISPLAY 0.872340 (-1673 3450);
PAINT GREEN (-1673 3450);
DISPLAY INVISIBLE (-1673 3450);
FORCEADD TAP..1
R 2
(-1675 3250);
FORCEPROP 3 LASTPIN (-1625 3250) SIG_NAME P3E_OCP_CPU0_PE3_C_TXP<4>
J 0
(-1615 3260);
DISPLAY 0.659574 (-1615 3260);
PAINT MONO (-1615 3260);
DISPLAY INVISIBLE (-1615 3260);
FORCEPROP 1 LASTPIN (-1625 3250) BN 4
J 2
(-1613 3258);
DISPLAY 0.617021 (-1613 3258);
PAINT GREEN (-1613 3258);
FORCEPROP 2 LAST CDS_LIB mstr_standard
J 0
(-1675 3250);
PAINT ORANGE (-1675 3250);
DISPLAY INVISIBLE (-1675 3250);
FORCEPROP 1 LAST BODY_TYPE PLUMBING
J 2
(-1675 3300);
DISPLAY 0.872340 (-1675 3300);
PAINT GREEN (-1675 3300);
DISPLAY INVISIBLE (-1675 3300);
FORCEPROP 1 LAST HDL_TAP TRUE
J 2
(-2000 3125);
DISPLAY 0.872340 (-2000 3125);
PAINT ORANGE (-2000 3125);
DISPLAY INVISIBLE (-2000 3125);
FORCEPROP 1 LAST PATH I90
J 2
(-1673 3250);
DISPLAY 0.872340 (-1673 3250);
PAINT GREEN (-1673 3250);
DISPLAY INVISIBLE (-1673 3250);
FORCEADD TAP..1
R 2
(-1950 3800);
FORCEPROP 3 LASTPIN (-1900 3800) SIG_NAME P3E_OCP_CPU0_PE3_C_TXN<7>
J 0
(-1890 3810);
DISPLAY 0.659574 (-1890 3810);
PAINT MONO (-1890 3810);
DISPLAY INVISIBLE (-1890 3810);
FORCEPROP 1 LASTPIN (-1900 3800) BN 7
J 2
(-1888 3808);
DISPLAY 0.617021 (-1888 3808);
PAINT GREEN (-1888 3808);
FORCEPROP 2 LAST CDS_LIB mstr_standard
J 0
(-1950 3800);
PAINT ORANGE (-1950 3800);
DISPLAY INVISIBLE (-1950 3800);
FORCEPROP 1 LAST BODY_TYPE PLUMBING
J 2
(-1950 3850);
DISPLAY 0.872340 (-1950 3850);
PAINT GREEN (-1950 3850);
DISPLAY INVISIBLE (-1950 3850);
FORCEPROP 1 LAST HDL_TAP TRUE
J 2
(-2275 3675);
DISPLAY 0.872340 (-2275 3675);
PAINT ORANGE (-2275 3675);
DISPLAY INVISIBLE (-2275 3675);
FORCEPROP 1 LAST PATH I95
J 2
(-1948 3800);
DISPLAY 0.872340 (-1948 3800);
PAINT GREEN (-1948 3800);
DISPLAY INVISIBLE (-1948 3800);
FORCEADD TAP..1
R 2
(-1950 3600);
FORCEPROP 3 LASTPIN (-1900 3600) SIG_NAME P3E_OCP_CPU0_PE3_C_TXN<6>
J 0
(-1890 3610);
DISPLAY 0.659574 (-1890 3610);
PAINT MONO (-1890 3610);
DISPLAY INVISIBLE (-1890 3610);
FORCEPROP 1 LASTPIN (-1900 3600) BN 6
J 2
(-1888 3608);
DISPLAY 0.617021 (-1888 3608);
PAINT GREEN (-1888 3608);
FORCEPROP 2 LAST CDS_LIB mstr_standard
J 0
(-1950 3600);
PAINT ORANGE (-1950 3600);
DISPLAY INVISIBLE (-1950 3600);
FORCEPROP 1 LAST BODY_TYPE PLUMBING
J 2
(-1950 3650);
DISPLAY 0.872340 (-1950 3650);
PAINT GREEN (-1950 3650);
DISPLAY INVISIBLE (-1950 3650);
FORCEPROP 1 LAST HDL_TAP TRUE
J 2
(-2275 3475);
DISPLAY 0.872340 (-2275 3475);
PAINT ORANGE (-2275 3475);
DISPLAY INVISIBLE (-2275 3475);
FORCEPROP 1 LAST PATH I96
J 2
(-1948 3600);
DISPLAY 0.872340 (-1948 3600);
PAINT GREEN (-1948 3600);
DISPLAY INVISIBLE (-1948 3600);
FORCEADD TAP..1
R 2
(-1950 3400);
FORCEPROP 3 LASTPIN (-1900 3400) SIG_NAME P3E_OCP_CPU0_PE3_C_TXN<5>
J 0
(-1890 3410);
DISPLAY 0.659574 (-1890 3410);
PAINT MONO (-1890 3410);
DISPLAY INVISIBLE (-1890 3410);
FORCEPROP 1 LASTPIN (-1900 3400) BN 5
J 2
(-1888 3408);
DISPLAY 0.617021 (-1888 3408);
PAINT GREEN (-1888 3408);
FORCEPROP 2 LAST CDS_LIB mstr_standard
J 0
(-1950 3400);
PAINT ORANGE (-1950 3400);
DISPLAY INVISIBLE (-1950 3400);
FORCEPROP 1 LAST BODY_TYPE PLUMBING
J 2
(-1950 3450);
DISPLAY 0.872340 (-1950 3450);
PAINT GREEN (-1950 3450);
DISPLAY INVISIBLE (-1950 3450);
FORCEPROP 1 LAST HDL_TAP TRUE
J 2
(-2275 3275);
DISPLAY 0.872340 (-2275 3275);
PAINT ORANGE (-2275 3275);
DISPLAY INVISIBLE (-2275 3275);
FORCEPROP 1 LAST PATH I97
J 2
(-1948 3400);
DISPLAY 0.872340 (-1948 3400);
PAINT GREEN (-1948 3400);
DISPLAY INVISIBLE (-1948 3400);
FORCEADD TAP..1
R 2
(-1950 3200);
FORCEPROP 3 LASTPIN (-1900 3200) SIG_NAME P3E_OCP_CPU0_PE3_C_TXN<4>
J 0
(-1890 3210);
DISPLAY 0.659574 (-1890 3210);
PAINT MONO (-1890 3210);
DISPLAY INVISIBLE (-1890 3210);
FORCEPROP 1 LASTPIN (-1900 3200) BN 4
J 2
(-1888 3208);
DISPLAY 0.617021 (-1888 3208);
PAINT GREEN (-1888 3208);
FORCEPROP 2 LAST CDS_LIB mstr_standard
J 0
(-1950 3200);
PAINT ORANGE (-1950 3200);
DISPLAY INVISIBLE (-1950 3200);
FORCEPROP 1 LAST BODY_TYPE PLUMBING
J 2
(-1950 3250);
DISPLAY 0.872340 (-1950 3250);
PAINT GREEN (-1950 3250);
DISPLAY INVISIBLE (-1950 3250);
FORCEPROP 1 LAST HDL_TAP TRUE
J 2
(-2275 3075);
DISPLAY 0.872340 (-2275 3075);
PAINT ORANGE (-2275 3075);
DISPLAY INVISIBLE (-2275 3075);
FORCEPROP 1 LAST PATH I98
J 2
(-1948 3200);
DISPLAY 0.872340 (-1948 3200);
PAINT GREEN (-1948 3200);
DISPLAY INVISIBLE (-1948 3200);
FORCEADD OFFPAGE..1
(-3050 4075);
FORCEPROP 2 LAST $XR0 106 
J 0
(-3302 4075);
DISPLAY 0.638298 (-3302 4075);
PAINT MONO (-3302 4075);
FORCEPROP 2 LAST CDS_LIB mstr_standard
J 0
(-3050 4075);
PAINT ORANGE (-3050 4075);
DISPLAY INVISIBLE (-3050 4075);
FORCEPROP 1 LAST OFFPAGE TRUE
J 0
(-2725 3950);
DISPLAY 0.872340 (-2725 3950);
PAINT GREEN (-2725 3950);
DISPLAY INVISIBLE (-2725 3950);
FORCEPROP 1 LAST COMMENT_BODY TRUE
J 0
(-2925 3975);
DISPLAY 0.872340 (-2925 3975);
PAINT GREEN (-2925 3975);
DISPLAY INVISIBLE (-2925 3975);
FORCEPROP 2 LAST PATH I99
J 0
(-3000 4150);
DISPLAY 1.021277 (-3000 4150);
PAINT ORANGE (-3000 4150);
DISPLAY INVISIBLE (-3000 4150);
FORCEADD DESIGN_NOTE..1
(1850 4775);
FORCEPROP 0 LAST L1 SWAPPED 15:8 WITH 7:0 ON 120-PIN CONNECTOR
J 0
(1650 4625);
DISPLAY 1.021277 (1650 4625);
PAINT ORANGE (1650 4625);
FORCEPROP 0 LAST L2 TO ELIMINATE ROUTING CROSSOVER.
J 0
(1650 4525);
DISPLAY 1.021277 (1650 4525);
PAINT ORANGE (1650 4525);
FORCEPROP 2 LAST CDS_LIB mstr_symbols
J 0
(1850 4775);
PAINT ORANGE (1850 4775);
DISPLAY INVISIBLE (1850 4775);
FORCEPROP 1 LAST COMMENT_BODY TRUE
J 0
(1875 4875);
DISPLAY 0.978723 (1875 4875);
PAINT ORANGE (1875 4875);
DISPLAY INVISIBLE (1875 4875);
FORCEADD DESIGN_NOTE..1
(525 4625);
FORCEPROP 0 LAST L1 13MM HT CONNECTOR IN SCHEMATIC
J 0
(325 4500);
DISPLAY 1.021277 (325 4500);
PAINT ORANGE (325 4500);
FORCEPROP 0 LAST L2 12MM HT CONNECTOR IN BOM
J 0
(325 4425);
DISPLAY 1.021277 (325 4425);
PAINT ORANGE (325 4425);
FORCEPROP 2 LAST CDS_LIB mstr_symbols
J 0
(525 4625);
PAINT ORANGE (525 4625);
DISPLAY INVISIBLE (525 4625);
FORCEPROP 1 LAST COMMENT_BODY TRUE
J 0
(550 4725);
DISPLAY 0.978723 (550 4725);
PAINT ORANGE (550 4725);
DISPLAY INVISIBLE (550 4725);
FORCEADD INTEL_CORP_BPAGE..1
(4050 475);
FORCEPROP 1 LAST CDS_CON_LAST_MODIFIED Tue Dec 01 11:52:16 2015
J 0
(2625 800);
PAINT ORANGE (2625 800);
DISPLAY INVISIBLE (2625 800);
FORCEPROP 1 LAST CUSTOM_TXT_CDS <CURRENT_DESIGN_SHEET> OF <TOTAL_DESIGN_SHEETS>
J 0
(3550 500);
PAINT GREEN (3550 500);
FORCEPROP 1 LAST CUSTOM_TXT_CDS <CON_LAST_MODIFIED>
J 0
(2125 825);
PAINT GREEN (2125 825);
FORCEPROP 2 LAST CUSTOM_TXT_CDS <XR_PAGE_TITLE>
J 0
(-3840 5725);
DISPLAY 0.638298 (-3840 5725);
PAINT PINK (-3840 5725);
DISPLAY INVISIBLE (-3840 5725);
FORCEPROP 1 LAST SCH_ADDRESS3 Santa Clara, CA 95052-8119
J 0
(75 500);
DISPLAY 0.617021 (75 500);
PAINT GREEN (75 500);
FORCEPROP 1 LAST SCH_ADDRESS2 P.O. BOX 58119
J 0
(75 550);
DISPLAY 0.617021 (75 550);
PAINT GREEN (75 550);
FORCEPROP 1 LAST SCH_ADDRESS1 2200 Mission College Blvd.
J 0
(75 600);
DISPLAY 0.617021 (75 600);
PAINT GREEN (75 600);
FORCEPROP 1 LAST SCH_TITLE OCP MODULE CONN B
J 0
(-3900 525);
DISPLAY 1.212766 (-3900 525);
PAINT ORANGE (-3900 525);
FORCEPROP 1 LAST SCH_REV 2.420
J 0
(3800 625);
DISPLAY 0.978723 (3800 625);
PAINT YELLOW (3800 625);
FORCEPROP 1 LAST SCH_DEPT BESD
J 1
(-400 575);
DISPLAY 1.212766 (-400 575);
PAINT YELLOW (-400 575);
FORCEPROP 1 LAST SCH_NUMBER H4694802
J 0
(2750 625);
DISPLAY 1.212766 (2750 625);
PAINT YELLOW (2750 625);
FORCEPROP 2 LAST PAGE_BORDER TRUE
J 0
(-3840 5725);
DISPLAY 0.638298 (-3840 5725);
PAINT PINK (-3840 5725);
DISPLAY INVISIBLE (-3840 5725);
FORCEPROP 2 LAST CDS_LIB mstr_symbols
J 0
(4050 475);
PAINT MONO (4050 475);
DISPLAY INVISIBLE (4050 475);
FORCEPROP 1 LAST COMMENT_BODY TRUE
J 0
(4062 487);
DISPLAY 0.468085 (4062 487);
PAINT GREEN (4062 487);
DISPLAY INVISIBLE (4062 487);
FORCEPROP 2 LAST CDS_XR_PAGE_TITLE CR-187 : @BASEBOARD_FAB2_LIB.BASEBOARD_FAB2(SCH_1):PAGE187
J 0
(-3840 5725);
DISPLAY 0.638298 (-3840 5725);
PAINT PINK (-3840 5725);
DISPLAY INVISIBLE (-3840 5725);
WIRE 17 -1 (1800 3950)(1800 3925);
WIRE 17 -1 (1800 3950)(2475 3950);
FORCEPROP 2 LAST SIG_NAME P3E_CPU0_PE3_OCP_RXN<7:0>
J 0
(1900 3973);
DISPLAY 0.617021 (1900 3973);
PAINT ORANGE (1900 3973);
WIRE 17 -1 (1600 4025)(1600 3975);
WIRE 17 -1 (1600 4025)(2475 4025);
FORCEPROP 2 LAST SIG_NAME P3E_CPU0_PE3_OCP_RXP<7:0>
J 0
(1900 4033);
DISPLAY 0.617021 (1900 4033);
PAINT ORANGE (1900 4033);
WIRE 17 -1 (1800 3775)(1800 3575);
WIRE 17 -1 (1800 3925)(1800 3775);
WIRE 17 -1 (1800 3575)(1800 3375);
WIRE 17 -1 (1800 3125)(1800 3375);
WIRE 17 -1 (1600 3175)(1600 3325);
WIRE 17 -1 (1600 2975)(1600 3175);
WIRE 17 -1 (1600 3525)(1600 3325);
WIRE 17 -1 (1600 3725)(1600 3525);
WIRE 17 -1 (1600 2775)(1600 2975);
WIRE 17 -1 (1600 2575)(1600 2775);
WIRE 17 -1 (1600 3975)(1600 3725);
WIRE 17 -1 (1800 2925)(1800 3125);
WIRE 17 -1 (1800 2925)(1800 2725);
WIRE 17 -1 (1800 2525)(1800 2725);
WIRE 17 -1 (-1725 2675)(-1725 2875);
WIRE 17 -1 (-1725 2475)(-1725 2675);
WIRE 17 -1 (-1725 3075)(-1725 2875);
WIRE 17 -1 (-1725 3075)(-1725 3275);
WIRE 17 -1 (-1725 3275)(-1725 3475);
WIRE 17 -1 (-1725 3675)(-1725 3475);
WIRE 17 -1 (-1725 3875)(-1725 3675);
WIRE 17 -1 (-1725 4075)(-1725 3875);
WIRE 17 -1 (-1725 4075)(-3000 4075);
FORCEPROP 0 LAST SIG_NAME P3E_OCP_CPU0_PE3_C_TXP<7:0>
J 0
(-3000 4085);
DISPLAY 0.617021 (-3000 4085);
PAINT ORANGE (-3000 4085);
WIRE 17 -1 (-2000 3025)(-2000 3225);
WIRE 17 -1 (-2000 2825)(-2000 3025);
WIRE 17 -1 (-2000 3425)(-2000 3225);
WIRE 17 -1 (-2000 3625)(-2000 3425);
WIRE 17 -1 (-2000 2625)(-2000 2825);
WIRE 17 -1 (-2000 2425)(-2000 2625);
WIRE 17 -1 (-2000 3825)(-2000 3625);
WIRE 17 -1 (-2000 4025)(-2000 3825);
WIRE 17 -1 (-2000 4025)(-3000 4025);
FORCEPROP 0 LAST SIG_NAME P3E_OCP_CPU0_PE3_C_TXN<7:0>
J 0
(-3000 4035);
DISPLAY 0.617021 (-3000 4035);
PAINT ORANGE (-3000 4035);
WIRE 16 -1 (250 4000)(625 4000);
WIRE 16 -1 (625 4000)(625 3850);
WIRE 16 -1 (250 3850)(625 3850);
WIRE 16 -1 (625 3850)(625 3800);
WIRE 16 -1 (250 3800)(625 3800);
WIRE 16 -1 (625 3800)(625 3650);
WIRE 16 -1 (250 3650)(625 3650);
WIRE 16 -1 (625 3650)(625 3600);
WIRE 16 -1 (250 3600)(625 3600);
WIRE 16 -1 (625 3600)(625 3450);
WIRE 16 -1 (250 3450)(625 3450);
WIRE 16 -1 (625 3450)(625 3400);
WIRE 16 -1 (250 3400)(625 3400);
WIRE 16 -1 (625 3400)(625 3250);
WIRE 16 -1 (250 3250)(625 3250);
WIRE 16 -1 (625 3250)(625 3200);
WIRE 16 -1 (250 3200)(625 3200);
WIRE 16 -1 (625 3200)(625 3050);
WIRE 16 -1 (250 3050)(625 3050);
WIRE 16 -1 (625 3050)(625 3000);
WIRE 16 -1 (250 3000)(625 3000);
WIRE 16 -1 (625 2850)(625 3000);
WIRE 16 -1 (250 2850)(625 2850);
WIRE 16 -1 (625 2850)(625 2800);
WIRE 16 -1 (250 2800)(625 2800);
WIRE 16 -1 (625 2800)(625 2650);
WIRE 16 -1 (250 2650)(625 2650);
WIRE 16 -1 (625 2650)(625 2600);
WIRE 16 -1 (250 2600)(625 2600);
WIRE 16 -1 (625 2600)(625 2450);
WIRE 16 -1 (250 2450)(625 2450);
WIRE 16 -1 (625 2450)(625 2400);
WIRE 16 -1 (250 2400)(625 2400);
WIRE 16 -1 (625 2400)(625 2250);
WIRE 16 -1 (250 2250)(625 2250);
WIRE 16 -1 (625 2250)(625 1950);
WIRE 16 -1 (-350 3900)(-725 3900);
WIRE 16 -1 (-725 3900)(-725 3750);
WIRE 16 -1 (-350 3750)(-725 3750);
WIRE 16 -1 (-725 3750)(-725 3700);
WIRE 16 -1 (-350 3700)(-725 3700);
WIRE 16 -1 (-725 3700)(-725 3550);
WIRE 16 -1 (-350 3550)(-725 3550);
WIRE 16 -1 (-725 3550)(-725 3500);
WIRE 16 -1 (-350 3500)(-725 3500);
WIRE 16 -1 (-725 3500)(-725 3350);
WIRE 16 -1 (-350 3350)(-725 3350);
WIRE 16 -1 (-725 3350)(-725 3300);
WIRE 16 -1 (-350 3300)(-725 3300);
WIRE 16 -1 (-725 3300)(-725 3150);
WIRE 16 -1 (-350 3150)(-725 3150);
WIRE 16 -1 (-725 3150)(-725 3100);
WIRE 16 -1 (-725 3100)(-350 3100);
WIRE 16 -1 (-725 3100)(-725 2950);
WIRE 16 -1 (-350 2950)(-725 2950);
WIRE 16 -1 (-725 2950)(-725 2900);
WIRE 16 -1 (-350 2900)(-725 2900);
WIRE 16 -1 (-725 2750)(-725 2900);
WIRE 16 -1 (-350 2750)(-725 2750);
WIRE 16 -1 (-725 2750)(-725 2700);
WIRE 16 -1 (-350 2700)(-725 2700);
WIRE 16 -1 (-725 2700)(-725 2550);
WIRE 16 -1 (-350 2550)(-725 2550);
WIRE 16 -1 (-725 2550)(-725 2500);
WIRE 16 -1 (-350 2500)(-725 2500);
WIRE 16 -1 (-725 2500)(-725 2350);
WIRE 16 -1 (-350 2350)(-725 2350);
WIRE 16 -1 (-725 2350)(-725 2300);
WIRE 16 -1 (-350 2300)(-725 2300);
WIRE 16 -1 (-725 2300)(-725 2150);
WIRE 16 -1 (-350 2150)(-725 2150);
WIRE 16 -1 (-725 2150)(-725 1900);
WIRE 16 -1 (1325 4050)(1075 4050);
WIRE 16 -1 (-350 4000)(-1000 4000);
WIRE 16 -1 (-1000 4050)(-1000 4000);
WIRE 16 -1 (-350 4050)(-1000 4050);
WIRE 16 -1 (-1000 4050)(-1000 4325);
WIRE 16 -1 (925 5250)(200 5250);
WIRE 16 -1 (925 5250)(925 5075);
WIRE 16 -1 (200 5250)(200 4775);
WIRE 16 -1 (200 5250)(-450 5250);
WIRE 16 -1 (-450 5250)(-450 4775);
WIRE 16 -1 (-450 5250)(-1150 5250);
WIRE 16 -1 (925 4775)(200 4775);
WIRE 16 -1 (200 4775)(-450 4775);
WIRE 16 -1 (925 4975)(925 5075);
WIRE 16 -1 (-3850 5075)(925 5075);
WIRE 16 -1 (-3850 5250)(-3850 5075);
WIRE 16 -1 (-3850 4975)(-3850 5075);
WIRE 16 -1 (925 4875)(925 4975);
WIRE 16 -1 (-3850 4975)(925 4975);
WIRE 16 -1 (-450 4775)(-1150 4775);
WIRE 16 -1 (925 4875)(925 4775);
WIRE 16 -1 (-1150 5250)(-1825 5250);
WIRE 16 -1 (-1150 5250)(-1150 4775);
WIRE 16 -1 (-1150 4775)(-1825 4775);
WIRE 16 -1 (-1825 5250)(-1825 4775);
WIRE 16 -1 (-1825 5250)(-2700 5250);
WIRE 16 -1 (-3850 4875)(925 4875);
WIRE 16 -1 (-3850 4975)(-3850 4875);
WIRE 16 -1 (-3850 5250)(-3550 5250);
WIRE 16 -1 (-3550 5250)(-2700 5250);
WIRE 16 -1 (-3550 5250)(-3550 4775);
WIRE 16 -1 (-3850 4875)(-3850 4775);
WIRE 16 -1 (-2700 5250)(-2700 4775);
WIRE 16 -1 (-1825 4775)(-2700 4775);
WIRE 16 -1 (-3550 4775)(-2700 4775);
WIRE 16 -1 (-3850 4775)(-3550 4775);
WIRE 16 -1 (-350 3200)(-1900 3200);
WIRE 16 -1 (-1625 2850)(-350 2850);
WIRE 16 -1 (-350 2800)(-1900 2800);
WIRE 16 -1 (-350 2600)(-1900 2600);
WIRE 16 -1 (-350 2400)(-1900 2400);
WIRE 16 -1 (-350 3650)(-1625 3650);
WIRE 16 -1 (-350 2450)(-1625 2450);
WIRE 16 -1 (-1625 3050)(-350 3050);
WIRE 16 -1 (-350 3250)(-1625 3250);
WIRE 16 -1 (-350 3400)(-1900 3400);
WIRE 16 -1 (-350 3450)(-1625 3450);
WIRE 16 -1 (-350 3600)(-1900 3600);
WIRE 16 -1 (-350 3800)(-1900 3800);
WIRE 16 -1 (-350 3850)(-1625 3850);
WIRE 16 -1 (-350 3000)(-1900 3000);
WIRE 16 -1 (-350 2650)(-1625 2650);
WIRE 16 -1 (-350 2200)(-1650 2200);
FORCEPROP 0 LAST SIG_NAME CLK_100M_MEZZ4_DN
J 1
(-1412 2210);
DISPLAY 0.617021 (-1412 2210);
PAINT ORANGE (-1412 2210);
WIRE 16 -1 (-350 2250)(-1650 2250);
FORCEPROP 0 LAST SIG_NAME CLK_100M_MEZZ4_DP
J 1
(-1412 2260);
DISPLAY 0.617021 (-1412 2260);
PAINT ORANGE (-1412 2260);
WIRE 16 -1 (-350 2100)(-1650 2100);
FORCEPROP 0 LAST SIG_NAME FM_OCP_MEZZB_PRES_N
J 1
(-1387 2110);
DISPLAY 0.617021 (-1387 2110);
PAINT ORANGE (-1387 2110);
WIRE 16 -1 (-350 3950)(-875 3950);
FORCEPROP 0 LAST SIG_NAME TP_RSVD_B1
J 0
(-835 3960);
DISPLAY 0.617021 (-835 3960);
PAINT ORANGE (-835 3960);
FORCEPROP 2 LASTPROP $XRERR UNIQUE?
J 0
(-1115 3950);
DISPLAY 0.638298 (-1115 3950);
PAINT MONO (-1115 3950);
DISPLAY INVISIBLE (-1115 3950);
WIRE 16 -1 (250 4050)(875 4050);
FORCEPROP 0 LAST SIG_NAME FM_MEZZ_PRSNTB1_N
J 1
(563 4060);
DISPLAY 0.617021 (563 4060);
PAINT ORANGE (563 4060);
FORCEPROP 2 LASTPROP $XRERR UNIQUE?
J 0
(323 4060);
DISPLAY 0.638298 (323 4060);
PAINT MONO (323 4060);
DISPLAY INVISIBLE (323 4060);
WIRE 16 -1 (250 3700)(1500 3700);
WIRE 16 -1 (250 3750)(1700 3750);
WIRE 16 -1 (250 3300)(1500 3300);
WIRE 16 -1 (250 3350)(1700 3350);
WIRE 16 -1 (250 3500)(1500 3500);
WIRE 16 -1 (250 3100)(1700 3100);
WIRE 16 -1 (250 2750)(1500 2750);
WIRE 16 -1 (1500 2950)(250 2950);
WIRE 16 -1 (250 2550)(1500 2550);
WIRE 16 -1 (250 2150)(1625 2150);
FORCEPROP 0 LAST SIG_NAME RST_PCIE_CPU_DEV2_R_N
J 1
(900 2160);
DISPLAY 0.617021 (900 2160);
PAINT ORANGE (900 2160);
FORCEPROP 2 LASTPROP $XRERR UNIQUE?
J 0
(660 2160);
DISPLAY 0.638298 (660 2160);
PAINT MONO (660 2160);
DISPLAY INVISIBLE (660 2160);
WIRE 16 -1 (250 2500)(1700 2500);
WIRE 16 -1 (250 2100)(1175 2100);
FORCEPROP 0 LAST SIG_NAME RST_PCIE_CPU_DEV3_R_N
J 1
(900 2110);
DISPLAY 0.617021 (900 2110);
PAINT ORANGE (900 2110);
FORCEPROP 2 LASTPROP $XRERR UNIQUE?
J 0
(660 2110);
DISPLAY 0.638298 (660 2110);
PAINT MONO (660 2110);
DISPLAY INVISIBLE (660 2110);
WIRE 16 -1 (250 2700)(1700 2700);
WIRE 16 -1 (250 2900)(1700 2900);
WIRE 16 -1 (250 3150)(1500 3150);
WIRE 16 -1 (250 3550)(1700 3550);
WIRE 16 -1 (250 3950)(1500 3950);
WIRE 16 -1 (250 3900)(1700 3900);
WIRE 16 -1 (250 2350)(1550 2350);
FORCEPROP 0 LAST SIG_NAME CLK_100M_MEZZ3_DP
J 1
(1263 2360);
DISPLAY 0.617021 (1263 2360);
PAINT ORANGE (1263 2360);
WIRE 16 -1 (250 2300)(1550 2300);
FORCEPROP 0 LAST SIG_NAME CLK_100M_MEZZ3_DN
J 1
(1263 2310);
DISPLAY 0.617021 (1263 2310);
PAINT ORANGE (1263 2310);
WIRE 16 -1 (250 2200)(2175 2200);
FORCEPROP 0 LAST SIG_NAME RST_PCIE_CPU_DEV1_R_N
J 1
(900 2210);
DISPLAY 0.617021 (900 2210);
PAINT ORANGE (900 2210);
FORCEPROP 2 LASTPROP $XRERR UNIQUE?
J 0
(660 2210);
DISPLAY 0.638298 (660 2210);
PAINT MONO (660 2210);
DISPLAY INVISIBLE (660 2210);
WIRE 16 -1 (1825 2150)(2950 2150);
FORCEPROP 0 LAST SIG_NAME RST_PCIE_CPU_DEV2_N
J 1
(2700 2160);
DISPLAY 0.617021 (2700 2160);
PAINT ORANGE (2700 2160);
WIRE 16 -1 (1375 2100)(2950 2100);
FORCEPROP 0 LAST SIG_NAME RST_PCIE_CPU_DEV3_N
J 1
(2700 2110);
DISPLAY 0.617021 (2700 2110);
PAINT ORANGE (2700 2110);
WIRE 16 -1 (2375 2200)(2950 2200);
FORCEPROP 0 LAST SIG_NAME RST_PCIE_CPU_DEV1_N
J 1
(2700 2210);
DISPLAY 0.617021 (2700 2210);
PAINT ORANGE (2700 2210);
DOT 1 (-725 3700);
DOT 1 (625 2250);
DOT 1 (625 3650);
DOT 1 (-725 2950);
DOT 1 (625 3800);
DOT 1 (625 3600);
DOT 1 (625 3400);
DOT 1 (625 3450);
DOT 1 (625 3200);
DOT 1 (625 3250);
DOT 1 (625 3850);
DOT 1 (625 2600);
DOT 1 (625 2650);
DOT 1 (625 2800);
DOT 1 (625 2850);
DOT 1 (625 3000);
DOT 1 (625 2400);
DOT 1 (625 2450);
DOT 1 (625 3050);
DOT 1 (-725 3350);
DOT 1 (-725 3150);
DOT 1 (-725 3100);
DOT 1 (-725 3300);
DOT 1 (-725 3550);
DOT 1 (-725 3750);
DOT 1 (-1000 4050);
DOT 1 (-725 3500);
DOT 1 (-725 2900);
DOT 1 (-725 2750);
DOT 1 (-725 2700);
DOT 1 (-725 2500);
DOT 1 (-725 2550);
DOT 1 (-725 2350);
DOT 1 (-725 2300);
DOT 1 (-725 2150);
DOT 1 (200 5250);
DOT 1 (925 5075);
DOT 1 (925 4875);
DOT 1 (925 4975);
DOT 1 (200 4775);
DOT 1 (-450 5250);
DOT 1 (-1150 5250);
DOT 1 (-1825 5250);
DOT 1 (-450 4775);
DOT 1 (-1150 4775);
DOT 1 (-1825 4775);
DOT 1 (-2700 5250);
DOT 1 (-3550 5250);
DOT 1 (-3850 5075);
DOT 1 (-2700 4775);
DOT 1 (-3550 4775);
DOT 1 (-3850 4875);
DOT 1 (-3850 4975);
FORCENOTE
61083-121402LF
(-3500 5000) 0;
DISPLAY LEFT (-3500 5000);
DISPLAY 1.021277 (-3500 5000);
PAINT PURPLE (-3500 5000);
FORCENOTE
FCI RECPT IPN ON CC
(225 5175) 0;
DISPLAY LEFT (225 5175);
DISPLAY 1.021277 (225 5175);
PAINT PURPLE (225 5175);
FORCENOTE
(12 MM STACK)
(225 5100) 0;
DISPLAY LEFT (225 5100);
DISPLAY 1.021277 (225 5100);
PAINT PURPLE (225 5100);
FORCENOTE
E67482-008
(225 4900) 0;
DISPLAY LEFT (225 4900);
DISPLAY 1.021277 (225 4900);
PAINT PURPLE (225 4900);
FORCENOTE
A28699-020
(225 5000) 0;
DISPLAY LEFT (225 5000);
DISPLAY 1.021277 (225 5000);
PAINT PURPLE (225 5000);
FORCENOTE
H87568-002
(225 4800) 0;
DISPLAY LEFT (225 4800);
DISPLAY 1.021277 (225 4800);
PAINT PURPLE (225 4800);
FORCENOTE
TO CPU0
(2350 3825) 0;
DISPLAY LEFT (2350 3825);
DISPLAY 1.021277 (2350 3825);
PAINT PURPLE (2350 3825);
FORCENOTE
10135583-642402LF
(-425 4800) 0;
DISPLAY LEFT (-425 4800);
DISPLAY 1.021277 (-425 4800);
PAINT PURPLE (-425 4800);
FORCENOTE
61082-082402LF
(-425 4900) 0;
DISPLAY LEFT (-425 4900);
DISPLAY 1.021277 (-425 4900);
PAINT PURPLE (-425 4900);
FORCENOTE
FCI RECPT # ON CC
(-425 5175) 0;
DISPLAY LEFT (-425 5175);
DISPLAY 1.021277 (-425 5175);
PAINT PURPLE (-425 5175);
FORCENOTE
61082-122402LF
(-425 5000) 0;
DISPLAY LEFT (-425 5000);
DISPLAY 1.021277 (-425 5000);
PAINT PURPLE (-425 5000);
FORCENOTE
(12MM STACK)
(-425 5100) 0;
DISPLAY LEFT (-425 5100);
DISPLAY 1.021277 (-425 5100);
PAINT PURPLE (-425 5100);
FORCENOTE
(5/8MM STACK)
(-1100 5100) 0;
DISPLAY LEFT (-1100 5100);
DISPLAY 1.021277 (-1100 5100);
PAINT PURPLE (-1100 5100);
FORCENOTE
10135583-641402LF
(-1775 4800) 0;
DISPLAY LEFT (-1775 4800);
DISPLAY 1.021277 (-1775 4800);
PAINT PURPLE (-1775 4800);
FORCENOTE
FCI RECPT # ON CC
(-1775 5175) 0;
DISPLAY LEFT (-1775 5175);
DISPLAY 1.021277 (-1775 5175);
PAINT PURPLE (-1775 5175);
FORCENOTE
H87568-001
(-1100 4800) 0;
DISPLAY LEFT (-1100 4800);
DISPLAY 1.021277 (-1100 4800);
PAINT PURPLE (-1100 4800);
FORCENOTE
FCI RECPT IPN ON CC
(-1125 5175) 0;
DISPLAY LEFT (-1125 5175);
DISPLAY 1.021277 (-1125 5175);
PAINT PURPLE (-1125 5175);
FORCENOTE
A28699-010
(-1100 5000) 0;
DISPLAY LEFT (-1100 5000);
DISPLAY 1.021277 (-1100 5000);
PAINT PURPLE (-1100 5000);
FORCENOTE
E67482-006
(-1100 4900) 0;
DISPLAY LEFT (-1100 4900);
DISPLAY 1.021277 (-1100 4900);
PAINT PURPLE (-1100 4900);
FORCENOTE
(5/8MM STACK)
(-1775 5100) 0;
DISPLAY LEFT (-1775 5100);
DISPLAY 1.021277 (-1775 5100);
PAINT PURPLE (-1775 5100);
FORCENOTE
61082-121402LF
(-1775 5000) 0;
DISPLAY LEFT (-1775 5000);
DISPLAY 1.021277 (-1775 5000);
PAINT PURPLE (-1775 5000);
FORCENOTE
61082-081402LF
(-1775 4900) 0;
DISPLAY LEFT (-1775 4900);
DISPLAY 1.021277 (-1775 4900);
PAINT PURPLE (-1775 4900);
FORCENOTE
61083-124402LF
(-2650 5000) 0;
DISPLAY LEFT (-2650 5000);
DISPLAY 1.021277 (-2650 5000);
PAINT PURPLE (-2650 5000);
FORCENOTE
10135584-644402LF
(-2650 4800) 0;
DISPLAY LEFT (-2650 4800);
DISPLAY 1.021277 (-2650 4800);
PAINT PURPLE (-2650 4800);
FORCENOTE
FCI PLUG # ON OCP MEZZ
(-2650 5175) 0;
DISPLAY LEFT (-2650 5175);
DISPLAY 1.021277 (-2650 5175);
PAINT PURPLE (-2650 5175);
FORCENOTE
(8/12 MM STACK)
(-2650 5100) 0;
DISPLAY LEFT (-2650 5100);
DISPLAY 1.021277 (-2650 5100);
PAINT PURPLE (-2650 5100);
FORCENOTE
61083-084402LF
(-2650 4900) 0;
DISPLAY LEFT (-2650 4900);
DISPLAY 1.021277 (-2650 4900);
PAINT PURPLE (-2650 4900);
FORCENOTE
FCI PLUG # ON OCP MEZZ
(-3500 5175) 0;
DISPLAY LEFT (-3500 5175);
DISPLAY 1.021277 (-3500 5175);
PAINT PURPLE (-3500 5175);
FORCENOTE
(5MM STACK)
(-3500 5100) 0;
DISPLAY LEFT (-3500 5100);
DISPLAY 1.021277 (-3500 5100);
PAINT PURPLE (-3500 5100);
FORCENOTE
10135584-641402LF
(-3500 4800) 0;
DISPLAY LEFT (-3500 4800);
DISPLAY 1.021277 (-3500 4800);
PAINT PURPLE (-3500 4800);
FORCENOTE
CONN
(-3825 5175) 0;
DISPLAY LEFT (-3825 5175);
DISPLAY 1.021277 (-3825 5175);
PAINT PURPLE (-3825 5175);
FORCENOTE
A (120P)
(-3825 5000) 0;
DISPLAY LEFT (-3825 5000);
DISPLAY 1.021277 (-3825 5000);
PAINT PURPLE (-3825 5000);
FORCENOTE
C (64P)
(-3825 4800) 0;
DISPLAY LEFT (-3825 4800);
DISPLAY 1.021277 (-3825 4800);
PAINT PURPLE (-3825 4800);
FORCENOTE
B (80P)
(-3825 4900) 0;
DISPLAY LEFT (-3825 4900);
DISPLAY 1.021277 (-3825 4900);
PAINT PURPLE (-3825 4900);
FORCENOTE
FROM CPU0
(-3100 3825) 0;
DISPLAY LEFT (-3100 3825);
DISPLAY 1.021277 (-3100 3825);
PAINT PURPLE (-3100 3825);
FORCENOTE
61082-081402LF
(-3500 4900) 0;
DISPLAY LEFT (-3500 4900);
DISPLAY 1.021277 (-3500 4900);
PAINT PURPLE (-3500 4900);
FORCENOTE
MATED HT CONNECTOR P/NS
(-3825 5275) 0;
DISPLAY LEFT (-3825 5275);
DISPLAY 1.021277 (-3825 5275);
PAINT PURPLE (-3825 5275);
QUIT
